FILE_TYPE = MACRO_DRAWING;
SET COLOR_WIRE YELLOW;
SET COLOR_PROP MONO;
SET COLOR_DOT WHITE;
SET COLOR_ARC YELLOW;
SET COLOR_BODY GREEN;
SET COLOR_NOTE MONO;
SET PROP_DISPLAY VALUE;
SET PAGE_NUMBER P161;
FORCEADD OFFPAGE..1
(-7375 1100);
FORCEPROP 2 LAST $XR0 147 
J 0
(-7627 1100);
DISPLAY 0.638298 (-7627 1100);
PAINT MONO (-7627 1100);
FORCEPROP 1 LAST OFFPAGE TRUE
J 0
(-7050 975);
DISPLAY 1.170213 (-7050 975);
PAINT GREEN (-7050 975);
DISPLAY INVISIBLE (-7050 975);
FORCEPROP 1 LAST COMMENT_BODY TRUE
J 0
(-7250 1000);
DISPLAY 1.170213 (-7250 1000);
PAINT PEACH (-7250 1000);
DISPLAY INVISIBLE (-7250 1000);
FORCEPROP 2 LAST PATH I100
J 0
(-7325 1175);
DISPLAY 1.021277 (-7325 1175);
PAINT ORANGE (-7325 1175);
DISPLAY INVISIBLE (-7325 1175);
FORCEPROP 2 LAST CDS_LIB mstr_standard
J 0
(-7375 1100);
PAINT ORANGE (-7375 1100);
DISPLAY INVISIBLE (-7375 1100);
FORCEADD RES..1
(-5600 1100);
FORCEPROP 1 LAST LOCATION R2U44
J 0
(-5650 1150);
DISPLAY 0.617021 (-5650 1150);
PAINT AQUA (-5650 1150);
FORCEPROP 1 LAST PART_NUMBER G21796-271
J 0
(-5650 1200);
DISPLAY 0.617021 (-5650 1200);
PAINT BLUE (-5650 1200);
FORCEPROP 1 LAST VALUE 221
J 2
(-5625 1000);
DISPLAY 0.617021 (-5625 1000);
PAINT SKYBLUE (-5625 1000);
FORCEPROP 1 LAST TOLERANCE 1.0%
J 0
(-5600 1000);
DISPLAY 0.617021 (-5600 1000);
PAINT SKYBLUE (-5600 1000);
FORCEPROP 1 LAST PACK_TYPE 0402
J 0
(-5350 950);
DISPLAY 0.617021 (-5350 950);
PAINT SKYBLUE (-5350 950);
FORCEPROP 1 LAST MATERIAL CHIP
J 0
(-5600 950);
DISPLAY 0.617021 (-5600 950);
PAINT SKYBLUE (-5600 950);
FORCEPROP 1 LAST WATTAGE 1/16W
J 2
(-5625 950);
DISPLAY 0.617021 (-5625 950);
PAINT SKYBLUE (-5625 950);
FORCEPROP 1 LASTPIN (-5500 1100) $PN 2
J 0
(-5538 1112);
DISPLAY 0.617021 (-5538 1112);
PAINT ORANGE (-5538 1112);
FORCEPROP 1 LASTPIN (-5700 1100) $PN 1
J 0
(-5688 1112);
DISPLAY 0.617021 (-5688 1112);
PAINT ORANGE (-5688 1112);
FORCEPROP 0 LAST BOM_COST SM_THERM
J 0
(-5650 1400);
DISPLAY 1.021277 (-5650 1400);
PAINT ORANGE (-5650 1400);
DISPLAY INVISIBLE (-5650 1400);
FORCEPROP 0 LAST ROOM CPU_FANS
J 0
(-5650 1300);
DISPLAY 1.021277 (-5650 1300);
PAINT ORANGE (-5650 1300);
DISPLAY INVISIBLE (-5650 1300);
FORCEPROP 1 LAST PATH I102
J 0
(-5650 1250);
DISPLAY 0.978723 (-5650 1250);
PAINT WHITE (-5650 1250);
DISPLAY INVISIBLE (-5650 1250);
FORCEPROP 2 LAST SEC_TYPE 0402
J 0
(-5650 1300);
DISPLAY 1.021277 (-5650 1300);
PAINT ORANGE (-5650 1300);
DISPLAY INVISIBLE (-5650 1300);
FORCEPROP 2 LAST SEC 1
J 0
(-5650 1300);
DISPLAY 0.680851 (-5650 1300);
PAINT MONO (-5650 1300);
DISPLAY INVISIBLE (-5650 1300);
FORCEPROP 2 LAST CDS_LIB mstr_discrete
J 0
(-5600 1100);
PAINT ORANGE (-5600 1100);
DISPLAY INVISIBLE (-5600 1100);
FORCEPROP 2 LAST CDS_LOCATION R2U44
J 0
(-5650 1150);
DISPLAY 0.617021 (-5650 1150);
PAINT AQUA (-5650 1150);
DISPLAY INVISIBLE (-5650 1150);
FORCEADD OFFPAGE..2
(-4900 1100);
FORCEPROP 2 LAST $XR0 161 
J 0
(-4711 1100);
DISPLAY 0.638298 (-4711 1100);
PAINT MONO (-4711 1100);
FORCEPROP 1 LAST COMMENT_BODY TRUE
J 0
(-4945 1005);
DISPLAY 0.872340 (-4945 1005);
PAINT GREEN (-4945 1005);
DISPLAY INVISIBLE (-4945 1005);
FORCEPROP 1 LAST OFFPAGE TRUE
J 0
(-4575 975);
DISPLAY 0.872340 (-4575 975);
PAINT GREEN (-4575 975);
DISPLAY INVISIBLE (-4575 975);
FORCEPROP 2 LAST PATH I103
J 0
(-4700 1150);
DISPLAY 1.021277 (-4700 1150);
PAINT ORANGE (-4700 1150);
DISPLAY INVISIBLE (-4700 1150);
FORCEPROP 2 LAST CDS_LIB mstr_standard
J 0
(-4900 1100);
PAINT ORANGE (-4900 1100);
DISPLAY INVISIBLE (-4900 1100);
FORCEADD GND..1
R 2
(-6200 475);
FORCEPROP 3 LASTPIN (-6200 525) SIG_NAME GND\g
J 0
(-6190 535);
DISPLAY 0.659574 (-6190 535);
PAINT MONO (-6190 535);
DISPLAY INVISIBLE (-6190 535);
FORCEPROP 1 LAST HDL_POWER GND
J 2
(-6200 625);
PAINT GREEN (-6200 625);
DISPLAY INVISIBLE (-6200 625);
FORCEPROP 2 LAST ROOM PLD
J 0
(-6400 555);
DISPLAY 1.595745 (-6400 555);
PAINT WHITE (-6400 555);
DISPLAY INVISIBLE (-6400 555);
FORCEPROP 1 LAST SIZE 1B
J 2
(-6275 425);
DISPLAY 2.446809 (-6275 425);
PAINT ORANGE (-6275 425);
DISPLAY INVISIBLE (-6275 425);
FORCEPROP 1 LAST VOLTAGE 0.0V
J 2
(-6155 432);
DISPLAY 0.340426 (-6155 432);
PAINT SKYBLUE (-6155 432);
DISPLAY INVISIBLE (-6155 432);
FORCEPROP 1 LAST BODY_TYPE PLUMBING
J 2
(-6155 432);
DISPLAY 0.340426 (-6155 432);
PAINT GREEN (-6155 432);
DISPLAY INVISIBLE (-6155 432);
FORCEPROP 1 LAST PATH I104
J 2
(-6275 475);
DISPLAY 0.872340 (-6275 475);
PAINT AQUA (-6275 475);
DISPLAY INVISIBLE (-6275 475);
FORCEPROP 2 LAST CDS_LIB mstr_symbols
J 0
(-6200 475);
PAINT ORANGE (-6200 475);
DISPLAY INVISIBLE (-6200 475);
FORCEADD P3V3_STBY..1
(-6200 850);
FORCEPROP 3 LASTPIN (-6200 800) SIG_NAME P3V3_STBY\g
J 0
(-6190 810);
DISPLAY 0.659574 (-6190 810);
PAINT MONO (-6190 810);
DISPLAY INVISIBLE (-6190 810);
FORCEPROP 1 LAST SIZE 1B
J 0
(-6155 872);
DISPLAY 0.340426 (-6155 872);
PAINT GREEN (-6155 872);
DISPLAY INVISIBLE (-6155 872);
FORCEPROP 1 LAST BODY_TYPE PLUMBING
J 0
(-6245 807);
DISPLAY 0.340426 (-6245 807);
PAINT GREEN (-6245 807);
DISPLAY INVISIBLE (-6245 807);
FORCEPROP 1 LAST VOLTAGE 3.3V
J 0
(-6245 807);
DISPLAY 0.340426 (-6245 807);
PAINT SKYBLUE (-6245 807);
DISPLAY INVISIBLE (-6245 807);
FORCEPROP 1 LAST HDL_POWER P3V3_STBY
J 0
(-6500 725);
DISPLAY 0.872340 (-6500 725);
PAINT ORANGE (-6500 725);
DISPLAY INVISIBLE (-6500 725);
FORCEPROP 1 LAST PATH I105
J 0
(-6155 852);
DISPLAY 0.340426 (-6155 852);
PAINT GREEN (-6155 852);
DISPLAY INVISIBLE (-6155 852);
FORCEPROP 2 LAST CDS_LIB mstr_symbols
J 0
(-6200 850);
PAINT ORANGE (-6200 850);
DISPLAY INVISIBLE (-6200 850);
FORCEADD P12V_FAN..1
(-1375 2575);
FORCEPROP 3 LASTPIN (-1375 2525) SIG_NAME P12V_FAN\g
J 0
(-1365 2535);
DISPLAY 0.659574 (-1365 2535);
PAINT MONO (-1365 2535);
DISPLAY INVISIBLE (-1365 2535);
FORCEPROP 2 LAST CDS_LIB mstr_symbols
J 0
(-1375 2575);
PAINT ORANGE (-1375 2575);
DISPLAY INVISIBLE (-1375 2575);
FORCEPROP 1 LAST PATH I108
J 0
(-1325 2600);
DISPLAY 0.872340 (-1325 2600);
PAINT AQUA (-1325 2600);
DISPLAY INVISIBLE (-1325 2600);
FORCEPROP 1 LAST HDL_POWER P12V_FAN
J 1
(-1375 2625);
DISPLAY 0.872340 (-1375 2625);
PAINT GREEN (-1375 2625);
DISPLAY INVISIBLE (-1375 2625);
FORCEPROP 1 LAST VOLTAGE 12.0V
J 0
(-1420 2532);
DISPLAY 0.340426 (-1420 2532);
PAINT SKYBLUE (-1420 2532);
DISPLAY INVISIBLE (-1420 2532);
FORCEPROP 1 LAST BODY_TYPE PLUMBING
J 0
(-1420 2532);
DISPLAY 0.340426 (-1420 2532);
PAINT GREEN (-1420 2532);
DISPLAY INVISIBLE (-1420 2532);
FORCEADD P12V_FAN..1
(-1500 4725);
FORCEPROP 3 LASTPIN (-1500 4675) SIG_NAME P12V_FAN\g
J 0
(-1490 4685);
DISPLAY 0.659574 (-1490 4685);
PAINT MONO (-1490 4685);
DISPLAY INVISIBLE (-1490 4685);
FORCEPROP 1 LAST BODY_TYPE PLUMBING
J 0
(-1545 4682);
DISPLAY 0.340426 (-1545 4682);
PAINT GREEN (-1545 4682);
DISPLAY INVISIBLE (-1545 4682);
FORCEPROP 1 LAST VOLTAGE 12.0V
J 0
(-1545 4682);
DISPLAY 0.340426 (-1545 4682);
PAINT SKYBLUE (-1545 4682);
DISPLAY INVISIBLE (-1545 4682);
FORCEPROP 1 LAST HDL_POWER P12V_FAN
J 1
(-1500 4775);
DISPLAY 0.872340 (-1500 4775);
PAINT GREEN (-1500 4775);
DISPLAY INVISIBLE (-1500 4775);
FORCEPROP 1 LAST PATH I110
J 0
(-1450 4750);
DISPLAY 0.872340 (-1450 4750);
PAINT AQUA (-1450 4750);
DISPLAY INVISIBLE (-1450 4750);
FORCEPROP 2 LAST CDS_LIB mstr_symbols
J 0
(-1500 4725);
PAINT ORANGE (-1500 4725);
DISPLAY INVISIBLE (-1500 4725);
FORCEADD GND..1
R 5
(-1200 1900);
FORCEPROP 3 LASTPIN (-1150 1900) SIG_NAME GND\g
J 0
(-1140 1910);
DISPLAY 0.659574 (-1140 1910);
PAINT MONO (-1140 1910);
DISPLAY INVISIBLE (-1140 1910);
FORCEPROP 1 LAST PATH I111
R 3
J 0
(-1200 1825);
DISPLAY 0.872340 (-1200 1825);
PAINT AQUA (-1200 1825);
DISPLAY INVISIBLE (-1200 1825);
FORCEPROP 1 LAST BODY_TYPE PLUMBING
R 3
J 0
(-1243 1945);
DISPLAY 0.340426 (-1243 1945);
PAINT GREEN (-1243 1945);
DISPLAY INVISIBLE (-1243 1945);
FORCEPROP 1 LAST SIZE 1B
R 3
J 0
(-1250 1825);
DISPLAY 1.170213 (-1250 1825);
PAINT AQUA (-1250 1825);
DISPLAY INVISIBLE (-1250 1825);
FORCEPROP 2 LAST CDS_LIB mstr_symbols
R 3
J 0
(-1200 1900);
PAINT ORANGE (-1200 1900);
DISPLAY INVISIBLE (-1200 1900);
FORCEPROP 1 LAST VOLTAGE 0.0V
R 3
J 0
(-1243 1945);
DISPLAY 0.340426 (-1243 1945);
PAINT SKYBLUE (-1243 1945);
DISPLAY INVISIBLE (-1243 1945);
FORCEPROP 1 LAST HDL_POWER GND
R 3
J 0
(-1050 1900);
DISPLAY 1.170213 (-1050 1900);
PAINT GREEN (-1050 1900);
DISPLAY INVISIBLE (-1050 1900);
FORCEADD CAP_A..1
(-5775 2150);
FORCEPROP 1 LASTPIN (-5775 2050) $PN 2
J 0
(-5765 2030);
DISPLAY 0.617021 (-5765 2030);
PAINT ORANGE (-5765 2030);
FORCEPROP 1 LASTPIN (-5775 2250) $PN 1
J 0
(-5765 2230);
DISPLAY 0.617021 (-5765 2230);
PAINT ORANGE (-5765 2230);
FORCEPROP 1 LAST LOCATION C1E22
J 0
(-5725 2250);
DISPLAY 0.617021 (-5725 2250);
PAINT AQUA (-5725 2250);
FORCEPROP 1 LAST VALUE 0.1UF
J 0
(-5725 2200);
DISPLAY 0.617021 (-5725 2200);
PAINT SKYBLUE (-5725 2200);
FORCEPROP 1 LAST VOLTAGE 16V
J 0
(-5725 2150);
DISPLAY 0.617021 (-5725 2150);
PAINT SKYBLUE (-5725 2150);
FORCEPROP 1 LAST PACK_TYPE 0402V
J 0
(-5725 1950);
DISPLAY 0.617021 (-5725 1950);
PAINT SKYBLUE (-5725 1950);
FORCEPROP 1 LAST PART_NUMBER A36096-030
J 0
(-5725 2000);
DISPLAY 0.617021 (-5725 2000);
PAINT BLUE (-5725 2000);
FORCEPROP 1 LAST MATERIAL X7R
J 0
(-5725 2050);
DISPLAY 0.617021 (-5725 2050);
PAINT SKYBLUE (-5725 2050);
FORCEPROP 1 LAST TOLERANCE 10%
J 0
(-5725 2100);
DISPLAY 0.617021 (-5725 2100);
PAINT SKYBLUE (-5725 2100);
FORCEPROP 2 LAST CDS_LIB dev_discrete
J 0
(-5775 2150);
PAINT ORANGE (-5775 2150);
DISPLAY INVISIBLE (-5775 2150);
FORCEPROP 2 LAST CDS_LOCATION C1E22
J 0
(-5725 2250);
DISPLAY 0.617021 (-5725 2250);
PAINT AQUA (-5725 2250);
DISPLAY INVISIBLE (-5725 2250);
FORCEPROP 2 LAST CDS_SEC 1
J 0
(-5725 2300);
PAINT ORANGE (-5725 2300);
DISPLAY INVISIBLE (-5725 2300);
FORCEPROP 2 LAST ROOM CPUFANS
J 0
(-5725 2300);
DISPLAY 1.021277 (-5725 2300);
PAINT ORANGE (-5725 2300);
DISPLAY INVISIBLE (-5725 2300);
FORCEPROP 1 LAST PATH I113
J 0
(-5725 2300);
DISPLAY 0.978723 (-5725 2300);
PAINT WHITE (-5725 2300);
DISPLAY INVISIBLE (-5725 2300);
FORCEPROP 2 LAST SEC 1
J 0
(-5725 2350);
DISPLAY 0.680851 (-5725 2350);
PAINT MONO (-5725 2350);
DISPLAY INVISIBLE (-5725 2350);
FORCEPROP 2 LAST SEC_TYPE 0402V
J 0
(-5725 2350);
DISPLAY 1.021277 (-5725 2350);
PAINT ORANGE (-5725 2350);
DISPLAY INVISIBLE (-5725 2350);
FORCEPROP 2 LAST BOM_COST SM_THERM
J 0
(-5725 2350);
DISPLAY 1.021277 (-5725 2350);
PAINT ORANGE (-5725 2350);
DISPLAY INVISIBLE (-5725 2350);
FORCEADD OFFPAGE..2
(-5300 2575);
FORCEPROP 2 LAST $XR1 198 
J 0
(-4991 2575);
DISPLAY 0.638298 (-4991 2575);
PAINT MONO (-4991 2575);
FORCEPROP 2 LAST $XR0 181 
J 0
(-5111 2575);
DISPLAY 0.638298 (-5111 2575);
PAINT MONO (-5111 2575);
FORCEPROP 1 LAST COMMENT_BODY TRUE
J 0
(-5345 2480);
DISPLAY 0.872340 (-5345 2480);
PAINT GREEN (-5345 2480);
DISPLAY INVISIBLE (-5345 2480);
FORCEPROP 2 LAST PATH I114
J 0
(-5125 2650);
DISPLAY 1.021277 (-5125 2650);
PAINT ORANGE (-5125 2650);
DISPLAY INVISIBLE (-5125 2650);
FORCEPROP 2 LAST CDS_LIB mstr_standard
J 0
(-5300 2575);
PAINT ORANGE (-5300 2575);
DISPLAY INVISIBLE (-5300 2575);
FORCEPROP 1 LAST OFFPAGE TRUE
J 0
(-4975 2450);
DISPLAY 0.872340 (-4975 2450);
PAINT GREEN (-4975 2450);
DISPLAY INVISIBLE (-4975 2450);
FORCEADD OFFPAGE..1
(-7150 2625);
FORCEPROP 2 LAST $XR2 198 
J 0
(-7642 2625);
DISPLAY 0.638298 (-7642 2625);
PAINT MONO (-7642 2625);
FORCEPROP 2 LAST $XR1 191 
J 0
(-7522 2625);
DISPLAY 0.638298 (-7522 2625);
PAINT MONO (-7522 2625);
FORCEPROP 2 LAST $XR0 181 
J 0
(-7402 2625);
DISPLAY 0.638298 (-7402 2625);
PAINT MONO (-7402 2625);
FORCEPROP 1 LAST OFFPAGE TRUE
J 0
(-6825 2500);
DISPLAY 1.170213 (-6825 2500);
PAINT GREEN (-6825 2500);
DISPLAY INVISIBLE (-6825 2500);
FORCEPROP 1 LAST COMMENT_BODY TRUE
J 0
(-7025 2525);
DISPLAY 1.170213 (-7025 2525);
PAINT PEACH (-7025 2525);
DISPLAY INVISIBLE (-7025 2525);
FORCEPROP 2 LAST CDS_LIB mstr_standard
J 0
(-7150 2625);
PAINT ORANGE (-7150 2625);
DISPLAY INVISIBLE (-7150 2625);
FORCEPROP 2 LAST PATH I115
J 0
(-7100 2700);
DISPLAY 1.021277 (-7100 2700);
PAINT ORANGE (-7100 2700);
DISPLAY INVISIBLE (-7100 2700);
FORCEADD OFFPAGE..1
(-7150 2525);
FORCEPROP 2 LAST $XR0 200 
J 0
(-7402 2525);
DISPLAY 0.638298 (-7402 2525);
PAINT MONO (-7402 2525);
FORCEPROP 1 LAST OFFPAGE TRUE
J 0
(-6825 2400);
DISPLAY 1.170213 (-6825 2400);
PAINT GREEN (-6825 2400);
DISPLAY INVISIBLE (-6825 2400);
FORCEPROP 1 LAST COMMENT_BODY TRUE
J 0
(-7025 2425);
DISPLAY 1.170213 (-7025 2425);
PAINT PEACH (-7025 2425);
DISPLAY INVISIBLE (-7025 2425);
FORCEPROP 2 LAST CDS_LIB mstr_standard
J 0
(-7150 2525);
PAINT ORANGE (-7150 2525);
DISPLAY INVISIBLE (-7150 2525);
FORCEPROP 2 LAST PATH I116
J 0
(-7100 2600);
DISPLAY 1.021277 (-7100 2600);
PAINT ORANGE (-7100 2600);
DISPLAY INVISIBLE (-7100 2600);
FORCEADD P3V3_STBY..1
(-5775 2350);
FORCEPROP 3 LASTPIN (-5775 2300) SIG_NAME P3V3_STBY\g
J 0
(-5765 2310);
DISPLAY 0.659574 (-5765 2310);
PAINT MONO (-5765 2310);
DISPLAY INVISIBLE (-5765 2310);
FORCEPROP 1 LAST HDL_POWER P3V3_STBY
J 0
(-6075 2225);
DISPLAY 0.872340 (-6075 2225);
PAINT ORANGE (-6075 2225);
DISPLAY INVISIBLE (-6075 2225);
FORCEPROP 1 LAST SIZE 1B
J 0
(-5730 2372);
DISPLAY 0.340426 (-5730 2372);
PAINT GREEN (-5730 2372);
DISPLAY INVISIBLE (-5730 2372);
FORCEPROP 2 LAST CDS_LIB mstr_symbols
J 0
(-5775 2350);
PAINT ORANGE (-5775 2350);
DISPLAY INVISIBLE (-5775 2350);
FORCEPROP 1 LAST PATH I117
J 0
(-5730 2352);
DISPLAY 0.340426 (-5730 2352);
PAINT GREEN (-5730 2352);
DISPLAY INVISIBLE (-5730 2352);
FORCEPROP 1 LAST VOLTAGE 3.3V
J 0
(-5820 2307);
DISPLAY 0.340426 (-5820 2307);
PAINT SKYBLUE (-5820 2307);
DISPLAY INVISIBLE (-5820 2307);
FORCEPROP 1 LAST BODY_TYPE PLUMBING
J 0
(-5820 2307);
DISPLAY 0.340426 (-5820 2307);
PAINT GREEN (-5820 2307);
DISPLAY INVISIBLE (-5820 2307);
FORCEADD GND..1
(-5775 1950);
FORCEPROP 3 LASTPIN (-5775 2000) SIG_NAME GND\g
J 0
(-5765 2010);
DISPLAY 0.659574 (-5765 2010);
PAINT MONO (-5765 2010);
DISPLAY INVISIBLE (-5765 2010);
FORCEPROP 1 LAST VOLTAGE 0.0V
J 0
(-5820 1907);
DISPLAY 0.340426 (-5820 1907);
PAINT SKYBLUE (-5820 1907);
DISPLAY INVISIBLE (-5820 1907);
FORCEPROP 2 LAST CDS_LIB mstr_symbols
J 0
(-5775 1950);
PAINT ORANGE (-5775 1950);
DISPLAY INVISIBLE (-5775 1950);
FORCEPROP 1 LAST SIZE 1B
J 0
(-5700 1900);
DISPLAY 1.170213 (-5700 1900);
PAINT AQUA (-5700 1900);
DISPLAY INVISIBLE (-5700 1900);
FORCEPROP 1 LAST BODY_TYPE PLUMBING
J 0
(-5820 1907);
DISPLAY 0.340426 (-5820 1907);
PAINT GREEN (-5820 1907);
DISPLAY INVISIBLE (-5820 1907);
FORCEPROP 1 LAST PATH I118
J 0
(-5700 1950);
DISPLAY 0.872340 (-5700 1950);
PAINT AQUA (-5700 1950);
DISPLAY INVISIBLE (-5700 1950);
FORCEPROP 1 LAST HDL_POWER GND
J 0
(-5775 2100);
DISPLAY 1.170213 (-5775 2100);
PAINT GREEN (-5775 2100);
DISPLAY INVISIBLE (-5775 2100);
FORCEADD P3V3_STBY..1
(-5950 3025);
FORCEPROP 3 LASTPIN (-5950 2975) SIG_NAME P3V3_STBY\g
J 0
(-5940 2985);
DISPLAY 0.659574 (-5940 2985);
PAINT MONO (-5940 2985);
DISPLAY INVISIBLE (-5940 2985);
FORCEPROP 1 LAST HDL_POWER P3V3_STBY
J 0
(-6250 2900);
DISPLAY 0.872340 (-6250 2900);
PAINT ORANGE (-6250 2900);
DISPLAY INVISIBLE (-6250 2900);
FORCEPROP 1 LAST PATH I119
J 0
(-5905 3027);
DISPLAY 0.340426 (-5905 3027);
PAINT GREEN (-5905 3027);
DISPLAY INVISIBLE (-5905 3027);
FORCEPROP 1 LAST BODY_TYPE PLUMBING
J 0
(-5995 2982);
DISPLAY 0.340426 (-5995 2982);
PAINT GREEN (-5995 2982);
DISPLAY INVISIBLE (-5995 2982);
FORCEPROP 1 LAST SIZE 1B
J 0
(-5905 3047);
DISPLAY 0.340426 (-5905 3047);
PAINT GREEN (-5905 3047);
DISPLAY INVISIBLE (-5905 3047);
FORCEPROP 2 LAST CDS_LIB mstr_symbols
J 0
(-5950 3025);
PAINT ORANGE (-5950 3025);
DISPLAY INVISIBLE (-5950 3025);
FORCEPROP 1 LAST VOLTAGE 3.3V
J 0
(-5995 2982);
DISPLAY 0.340426 (-5995 2982);
PAINT SKYBLUE (-5995 2982);
DISPLAY INVISIBLE (-5995 2982);
FORCEADD RES..2
(-5950 2800);
FORCEPROP 1 LASTPIN (-5950 2700) $PN 2
J 0
(-5945 2710);
DISPLAY 0.617021 (-5945 2710);
PAINT ORANGE (-5945 2710);
FORCEPROP 1 LASTPIN (-5950 2900) $PN 1
J 0
(-5945 2862);
DISPLAY 0.617021 (-5945 2862);
PAINT ORANGE (-5945 2862);
FORCEPROP 1 LAST PACK_TYPE 0402
J 0
(-5910 2625);
DISPLAY 0.617021 (-5910 2625);
PAINT SKYBLUE (-5910 2625);
FORCEPROP 1 LAST TOLERANCE 1%
J 0
(-5905 2825);
DISPLAY 0.617021 (-5905 2825);
PAINT SKYBLUE (-5905 2825);
FORCEPROP 1 LAST VALUE 10.0K
J 0
(-5905 2875);
DISPLAY 0.617021 (-5905 2875);
PAINT SKYBLUE (-5905 2875);
FORCEPROP 1 LAST LOCATION R1E11
J 0
(-5905 2925);
DISPLAY 0.617021 (-5905 2925);
PAINT AQUA (-5905 2925);
FORCEPROP 1 LAST WATTAGE 1/16W
J 0
(-5910 2775);
DISPLAY 0.617021 (-5910 2775);
PAINT SKYBLUE (-5910 2775);
FORCEPROP 1 LAST MATERIAL EMPTY
J 0
(-5910 2725);
DISPLAY 0.617021 (-5910 2725);
PAINT RED (-5910 2725);
FORCEPROP 1 LAST PART_NUMBER G21796-016
J 0
(-5910 2675);
DISPLAY 0.617021 (-5910 2675);
PAINT BLUE (-5910 2675);
FORCEPROP 2 LAST CDS_LIB mstr_discrete
J 0
(-5950 2800);
PAINT ORANGE (-5950 2800);
DISPLAY INVISIBLE (-5950 2800);
FORCEPROP 2 LAST CDS_LOCATION R1E11
J 0
(-5905 2925);
DISPLAY 0.617021 (-5905 2925);
PAINT AQUA (-5905 2925);
DISPLAY INVISIBLE (-5905 2925);
FORCEPROP 0 LAST ROOM CPU_FANS
J 0
(-5900 3025);
DISPLAY 1.021277 (-5900 3025);
PAINT ORANGE (-5900 3025);
DISPLAY INVISIBLE (-5900 3025);
FORCEPROP 1 LAST PATH I120
J 0
(-5900 2975);
DISPLAY 0.978723 (-5900 2975);
PAINT WHITE (-5900 2975);
DISPLAY INVISIBLE (-5900 2975);
FORCEPROP 2 LAST SEC 1
J 0
(-5900 3025);
DISPLAY 0.680851 (-5900 3025);
PAINT MONO (-5900 3025);
DISPLAY INVISIBLE (-5900 3025);
FORCEPROP 2 LAST SEC_TYPE 0402
J 0
(-5900 3025);
DISPLAY 1.021277 (-5900 3025);
PAINT ORANGE (-5900 3025);
DISPLAY INVISIBLE (-5900 3025);
FORCEPROP 0 LAST BOM_COST SM_THERM
J 0
(-5900 3125);
DISPLAY 1.021277 (-5900 3125);
PAINT ORANGE (-5900 3125);
DISPLAY INVISIBLE (-5900 3125);
FORCEADD TTL1G08..1
(-6250 2575);
FORCEPROP 1 LAST VALUE NC7SZ08
J 1
(-6250 2450);
DISPLAY 0.617021 (-6250 2450);
PAINT SKYBLUE (-6250 2450);
FORCEPROP 2 LASTPIN (-6400 2525) $PN 2
J 2
(-6410 2535);
DISPLAY 0.617021 (-6410 2535);
PAINT ORANGE (-6410 2535);
FORCEPROP 2 LASTPIN (-6400 2625) $PN 1
J 2
(-6410 2635);
DISPLAY 0.617021 (-6410 2635);
PAINT ORANGE (-6410 2635);
FORCEPROP 1 LAST MATERIAL IC
J 1
(-6275 2785);
DISPLAY 0.617021 (-6275 2785);
PAINT SKYBLUE (-6275 2785);
FORCEPROP 1 LAST PACK_TYPE SOTLF
J 1
(-6275 2750);
DISPLAY 0.617021 (-6275 2750);
PAINT SKYBLUE (-6275 2750);
FORCEPROP 1 LAST LOCATION U1E2
J 1
(-6275 2710);
DISPLAY 0.617021 (-6275 2710);
PAINT AQUA (-6275 2710);
FORCEPROP 1 LAST PART_NUMBER D10321-001
J 1
(-6275 2675);
DISPLAY 0.617021 (-6275 2675);
PAINT BLUE (-6275 2675);
FORCEPROP 1 LAST POWER_GROUP VCC=P3V3_STBY;GND=GND;
J 1
(-6225 2400);
DISPLAY 0.617021 (-6225 2400);
PAINT ORANGE (-6225 2400);
FORCEPROP 2 LASTPIN (-6100 2575) $PN 4
J 0
(-6090 2585);
DISPLAY 0.617021 (-6090 2585);
PAINT ORANGE (-6090 2585);
FORCEPROP 2 LAST CDS_LOCATION U1E2
J 1
(-6275 2710);
DISPLAY 0.617021 (-6275 2710);
PAINT AQUA (-6275 2710);
DISPLAY INVISIBLE (-6275 2710);
FORCEPROP 2 LAST CDS_LIB mstr_ttl
J 0
(-6250 2575);
PAINT ORANGE (-6250 2575);
DISPLAY INVISIBLE (-6250 2575);
FORCEPROP 0 LAST ROOM CPU_FANS
J 0
(-6275 2875);
DISPLAY 1.021277 (-6275 2875);
PAINT ORANGE (-6275 2875);
DISPLAY INVISIBLE (-6275 2875);
FORCEPROP 1 LAST PATH I121
J 1
(-6270 2840);
DISPLAY 0.702128 (-6270 2840);
PAINT WHITE (-6270 2840);
DISPLAY INVISIBLE (-6270 2840);
FORCEPROP 2 LAST SEC_TYPE SOTLF
J 0
(-6250 2875);
DISPLAY 1.021277 (-6250 2875);
PAINT ORANGE (-6250 2875);
DISPLAY INVISIBLE (-6250 2875);
FORCEPROP 2 LAST SEC 1
J 0
(-6250 2875);
DISPLAY 0.680851 (-6250 2875);
PAINT MONO (-6250 2875);
DISPLAY INVISIBLE (-6250 2875);
FORCEPROP 0 LAST BOM_COST SM_THERM
J 0
(-6275 2875);
DISPLAY 1.021277 (-6275 2875);
PAINT ORANGE (-6275 2875);
DISPLAY INVISIBLE (-6275 2875);
FORCEADD GND..1
R 5
(-1100 3975);
FORCEPROP 3 LASTPIN (-1050 3975) SIG_NAME GND\g
J 0
(-1040 3985);
DISPLAY 0.659574 (-1040 3985);
PAINT MONO (-1040 3985);
DISPLAY INVISIBLE (-1040 3985);
FORCEPROP 1 LAST HDL_POWER GND
R 3
J 0
(-950 3975);
DISPLAY 1.170213 (-950 3975);
PAINT GREEN (-950 3975);
DISPLAY INVISIBLE (-950 3975);
FORCEPROP 1 LAST PATH I122
R 3
J 0
(-1100 3900);
DISPLAY 0.872340 (-1100 3900);
PAINT AQUA (-1100 3900);
DISPLAY INVISIBLE (-1100 3900);
FORCEPROP 2 LAST CDS_LIB mstr_symbols
J 0
(-1100 3975);
PAINT ORANGE (-1100 3975);
DISPLAY INVISIBLE (-1100 3975);
FORCEPROP 1 LAST SIZE 1B
R 3
J 0
(-1150 3900);
DISPLAY 1.170213 (-1150 3900);
PAINT AQUA (-1150 3900);
DISPLAY INVISIBLE (-1150 3900);
FORCEPROP 1 LAST BODY_TYPE PLUMBING
R 3
J 0
(-1143 4020);
DISPLAY 0.340426 (-1143 4020);
PAINT GREEN (-1143 4020);
DISPLAY INVISIBLE (-1143 4020);
FORCEPROP 1 LAST VOLTAGE 0.0V
R 3
J 0
(-1143 4020);
DISPLAY 0.340426 (-1143 4020);
PAINT SKYBLUE (-1143 4020);
DISPLAY INVISIBLE (-1143 4020);
FORCEADD GND..1
(-1125 4075);
FORCEPROP 3 LASTPIN (-1125 4125) SIG_NAME GND\g
J 0
(-1115 4135);
DISPLAY 0.659574 (-1115 4135);
PAINT MONO (-1115 4135);
DISPLAY INVISIBLE (-1115 4135);
FORCEPROP 1 LAST BODY_TYPE PLUMBING
J 0
(-1170 4032);
DISPLAY 0.340426 (-1170 4032);
PAINT GREEN (-1170 4032);
DISPLAY INVISIBLE (-1170 4032);
FORCEPROP 1 LAST VOLTAGE 0.0V
J 0
(-1170 4032);
DISPLAY 0.340426 (-1170 4032);
PAINT SKYBLUE (-1170 4032);
DISPLAY INVISIBLE (-1170 4032);
FORCEPROP 1 LAST SIZE 1B
J 0
(-1050 4025);
DISPLAY 1.170213 (-1050 4025);
PAINT AQUA (-1050 4025);
DISPLAY INVISIBLE (-1050 4025);
FORCEPROP 1 LAST PATH I13
J 0
(-1050 4075);
DISPLAY 0.872340 (-1050 4075);
PAINT AQUA (-1050 4075);
DISPLAY INVISIBLE (-1050 4075);
FORCEPROP 2 LAST CDS_LIB mstr_symbols
J 0
(-1125 4075);
PAINT ORANGE (-1125 4075);
DISPLAY INVISIBLE (-1125 4075);
FORCEPROP 1 LAST HDL_POWER GND
J 0
(-1125 4225);
DISPLAY 1.170213 (-1125 4225);
PAINT GREEN (-1125 4225);
DISPLAY INVISIBLE (-1125 4225);
FORCEADD LOTES-CON4-S1-GP..1
(-600 3875);
FORCEPROP 1 LAST VALUE LOTES-CON4-S1-GP
J 0
(-675 3695);
DISPLAY 0.617021 (-675 3695);
PAINT GREEN (-675 3695);
FORCEPROP 1 LAST LOCATION J1F2
J 0
(-675 4045);
DISPLAY 0.617021 (-675 4045);
PAINT GREEN (-675 4045);
FORCEPROP 2 LASTPIN (-825 3775) $PN 4
J 2
(-835 3785);
DISPLAY 0.808511 (-835 3785);
PAINT ORANGE (-835 3785);
FORCEPROP 2 LASTPIN (-825 3825) $PN 3
J 2
(-835 3835);
DISPLAY 0.808511 (-835 3835);
PAINT ORANGE (-835 3835);
FORCEPROP 2 LASTPIN (-825 3875) $PN 2
J 2
(-835 3885);
DISPLAY 0.808511 (-835 3885);
PAINT ORANGE (-835 3885);
FORCEPROP 2 LASTPIN (-825 3975) $PN 1
J 2
(-835 3985);
DISPLAY 0.808511 (-835 3985);
PAINT ORANGE (-835 3985);
FORCEPROP 2 LASTPIN (-475 3825) $PN NP1
J 0
(-465 3835);
DISPLAY 0.808511 (-465 3835);
PAINT ORANGE (-465 3835);
FORCEPROP 1 LAST PATH I139
J 0
(-600 3915);
DISPLAY 0.617021 (-600 3915);
PAINT GREEN (-600 3915);
DISPLAY INVISIBLE (-600 3915);
FORCEPROP 0 LAST CDS_SEC 1
J 0
(-675 4075);
DISPLAY INVISIBLE (-675 4075);
FORCEPROP 1 LAST CDS_LMAN_SYM_OUTLINE -75,150,75,-150
J 0
(-600 3875);
DISPLAY 0.468085 (-600 3875);
PAINT GREEN (-600 3875);
DISPLAY INVISIBLE (-600 3875);
FORCEPROP 2 LAST CDS_LIB w_hdl
J 0
(-600 3875);
PAINT MONO (-600 3875);
DISPLAY INVISIBLE (-600 3875);
FORCEPROP 1 LAST PART_NUMBER 021.60521.0104
J 0
(-600 3835);
DISPLAY 0.617021 (-600 3835);
PAINT GREEN (-600 3835);
DISPLAY INVISIBLE (-600 3835);
FORCEPROP 2 LAST SEC_TYPE CONN-G7
J 0
(-675 4075);
DISPLAY 1.021277 (-675 4075);
PAINT ORANGE (-675 4075);
DISPLAY INVISIBLE (-675 4075);
FORCEPROP 2 LAST SEC 1
J 0
(-675 4075);
DISPLAY 0.680851 (-675 4075);
PAINT MONO (-675 4075);
DISPLAY INVISIBLE (-675 4075);
FORCEPROP 1 LAST PACK_TYPE CONN-G7
J 0
(-600 3875);
DISPLAY 0.617021 (-600 3875);
PAINT GREEN (-600 3875);
DISPLAY INVISIBLE (-600 3875);
FORCEPROP 0 LAST CDS_LOCATION J1F2
J 0
(-675 4075);
DISPLAY INVISIBLE (-675 4075);
FORCEADD LOTES-CON4-S1-GP..1
(-650 1800);
FORCEPROP 1 LAST VALUE LOTES-CON4-S1-GP
J 0
(-725 1620);
DISPLAY 0.617021 (-725 1620);
PAINT GREEN (-725 1620);
FORCEPROP 2 LASTPIN (-875 1700) $PN 4
J 2
(-885 1710);
DISPLAY 0.808511 (-885 1710);
PAINT ORANGE (-885 1710);
FORCEPROP 2 LASTPIN (-875 1900) $PN 1
J 2
(-885 1910);
DISPLAY 0.808511 (-885 1910);
PAINT ORANGE (-885 1910);
FORCEPROP 2 LASTPIN (-875 1800) $PN 2
J 2
(-885 1810);
DISPLAY 0.808511 (-885 1810);
PAINT ORANGE (-885 1810);
FORCEPROP 2 LASTPIN (-525 1750) $PN NP1
J 0
(-515 1760);
DISPLAY 0.808511 (-515 1760);
PAINT ORANGE (-515 1760);
FORCEPROP 2 LASTPIN (-875 1750) $PN 3
J 2
(-885 1760);
DISPLAY 0.808511 (-885 1760);
PAINT ORANGE (-885 1760);
FORCEPROP 1 LAST LOCATION J10W1
J 0
(-725 1970);
DISPLAY 0.617021 (-725 1970);
PAINT GREEN (-725 1970);
FORCEPROP 0 LAST CDS_SEC 1
J 0
(-725 2000);
DISPLAY INVISIBLE (-725 2000);
FORCEPROP 1 LAST CDS_LMAN_SYM_OUTLINE -75,150,75,-150
J 0
(-650 1800);
DISPLAY 0.468085 (-650 1800);
PAINT GREEN (-650 1800);
DISPLAY INVISIBLE (-650 1800);
FORCEPROP 2 LAST CDS_LIB w_hdl
J 0
(-650 1800);
PAINT MONO (-650 1800);
DISPLAY INVISIBLE (-650 1800);
FORCEPROP 1 LAST PART_NUMBER 021.60521.0104
J 0
(-650 1760);
DISPLAY 0.617021 (-650 1760);
PAINT GREEN (-650 1760);
DISPLAY INVISIBLE (-650 1760);
FORCEPROP 2 LAST SEC_TYPE CONN-G7
J 0
(-725 2000);
DISPLAY 1.021277 (-725 2000);
PAINT ORANGE (-725 2000);
DISPLAY INVISIBLE (-725 2000);
FORCEPROP 2 LAST SEC 1
J 0
(-725 2000);
DISPLAY 0.680851 (-725 2000);
PAINT MONO (-725 2000);
DISPLAY INVISIBLE (-725 2000);
FORCEPROP 1 LAST PACK_TYPE CONN-G7
J 0
(-650 1800);
DISPLAY 0.617021 (-650 1800);
PAINT GREEN (-650 1800);
DISPLAY INVISIBLE (-650 1800);
FORCEPROP 1 LAST PATH I140
J 0
(-650 1840);
DISPLAY 0.617021 (-650 1840);
PAINT GREEN (-650 1840);
DISPLAY INVISIBLE (-650 1840);
FORCEPROP 0 LAST CDS_LOCATION J10W1
J 0
(-725 2000);
DISPLAY INVISIBLE (-725 2000);
FORCEADD CAP_A..1
(-1000 2275);
FORCEPROP 1 LAST PACK_TYPE 0402V
J 0
(-950 2075);
DISPLAY 0.617021 (-950 2075);
PAINT SKYBLUE (-950 2075);
FORCEPROP 1 LASTPIN (-1000 2175) $PN 2
J 0
(-990 2155);
DISPLAY 0.617021 (-990 2155);
PAINT ORANGE (-990 2155);
FORCEPROP 1 LASTPIN (-1000 2375) $PN 1
J 0
(-990 2355);
DISPLAY 0.617021 (-990 2355);
PAINT ORANGE (-990 2355);
FORCEPROP 1 LAST LOCATION C9M5
J 0
(-950 2375);
DISPLAY 0.617021 (-950 2375);
PAINT AQUA (-950 2375);
FORCEPROP 1 LAST VALUE 0.1UF
J 0
(-950 2325);
DISPLAY 0.617021 (-950 2325);
PAINT SKYBLUE (-950 2325);
FORCEPROP 1 LAST VOLTAGE 16V
J 0
(-950 2275);
DISPLAY 0.617021 (-950 2275);
PAINT SKYBLUE (-950 2275);
FORCEPROP 1 LAST PART_NUMBER A36096-030
J 0
(-950 2125);
DISPLAY 0.617021 (-950 2125);
PAINT BLUE (-950 2125);
FORCEPROP 1 LAST MATERIAL X7R
J 0
(-950 2175);
DISPLAY 0.617021 (-950 2175);
PAINT SKYBLUE (-950 2175);
FORCEPROP 1 LAST TOLERANCE 10%
J 0
(-950 2225);
DISPLAY 0.617021 (-950 2225);
PAINT SKYBLUE (-950 2225);
FORCEPROP 2 LAST CDS_LOCATION C9M5
J 0
(-950 2375);
DISPLAY 0.617021 (-950 2375);
PAINT AQUA (-950 2375);
DISPLAY INVISIBLE (-950 2375);
FORCEPROP 0 LAST BOM_COST SM_THERM
J 0
(-950 2425);
DISPLAY 1.021277 (-950 2425);
PAINT ORANGE (-950 2425);
DISPLAY INVISIBLE (-950 2425);
FORCEPROP 2 LAST CDS_SEC 1
J 0
(-950 2425);
PAINT ORANGE (-950 2425);
DISPLAY INVISIBLE (-950 2425);
FORCEPROP 2 LAST SEC_TYPE 0402V
J 0
(-950 2475);
DISPLAY 1.021277 (-950 2475);
PAINT ORANGE (-950 2475);
DISPLAY INVISIBLE (-950 2475);
FORCEPROP 2 LAST SEC 1
J 0
(-950 2475);
DISPLAY 0.680851 (-950 2475);
PAINT MONO (-950 2475);
DISPLAY INVISIBLE (-950 2475);
FORCEPROP 0 LAST ROOM CPU_FANS
J 0
(-950 2475);
DISPLAY 1.021277 (-950 2475);
PAINT ORANGE (-950 2475);
DISPLAY INVISIBLE (-950 2475);
FORCEPROP 1 LAST PATH I26
J 0
(-950 2425);
DISPLAY 0.978723 (-950 2425);
PAINT WHITE (-950 2425);
DISPLAY INVISIBLE (-950 2425);
FORCEPROP 2 LAST CDS_LIB dev_discrete
J 0
(-1000 2275);
PAINT ORANGE (-1000 2275);
DISPLAY INVISIBLE (-1000 2275);
FORCEADD CAP..1
(-1300 2275);
FORCEPROP 1 LAST PART_NUMBER C95333-007
J 0
(-1250 2125);
DISPLAY 0.617021 (-1250 2125);
PAINT BLUE (-1250 2125);
FORCEPROP 1 LAST VALUE 10UF
J 0
(-1250 2325);
DISPLAY 0.617021 (-1250 2325);
PAINT SKYBLUE (-1250 2325);
FORCEPROP 1 LAST LOCATION C9M4
J 0
(-1250 2375);
DISPLAY 0.617021 (-1250 2375);
PAINT AQUA (-1250 2375);
FORCEPROP 1 LAST VOLTAGE 16V
J 0
(-1250 2275);
DISPLAY 0.617021 (-1250 2275);
PAINT SKYBLUE (-1250 2275);
FORCEPROP 1 LAST TOLERANCE 10%
J 0
(-1250 2225);
DISPLAY 0.617021 (-1250 2225);
PAINT SKYBLUE (-1250 2225);
FORCEPROP 1 LAST MATERIAL X6S
J 0
(-1250 2175);
DISPLAY 0.617021 (-1250 2175);
PAINT SKYBLUE (-1250 2175);
FORCEPROP 1 LAST PACK_TYPE 0805
J 0
(-1250 2075);
DISPLAY 0.617021 (-1250 2075);
PAINT SKYBLUE (-1250 2075);
FORCEPROP 1 LASTPIN (-1300 2375) $PN 1
J 0
(-1290 2355);
DISPLAY 0.617021 (-1290 2355);
PAINT ORANGE (-1290 2355);
FORCEPROP 1 LASTPIN (-1300 2175) $PN 2
J 0
(-1290 2155);
DISPLAY 0.617021 (-1290 2155);
PAINT ORANGE (-1290 2155);
FORCEPROP 0 LAST ROOM CPU_FANS
J 0
(-1250 2475);
DISPLAY 1.021277 (-1250 2475);
PAINT ORANGE (-1250 2475);
DISPLAY INVISIBLE (-1250 2475);
FORCEPROP 0 LAST BOM_COST SM_THERM
J 0
(-1250 2425);
DISPLAY 1.021277 (-1250 2425);
PAINT ORANGE (-1250 2425);
DISPLAY INVISIBLE (-1250 2425);
FORCEPROP 2 LAST SEC_TYPE 0805
J 0
(-1250 2475);
DISPLAY 1.021277 (-1250 2475);
PAINT ORANGE (-1250 2475);
DISPLAY INVISIBLE (-1250 2475);
FORCEPROP 2 LAST SEC 1
J 0
(-1250 2475);
DISPLAY 0.680851 (-1250 2475);
PAINT MONO (-1250 2475);
DISPLAY INVISIBLE (-1250 2475);
FORCEPROP 2 LAST CDS_LOCATION C9M4
J 0
(-1250 2375);
DISPLAY 0.617021 (-1250 2375);
PAINT AQUA (-1250 2375);
DISPLAY INVISIBLE (-1250 2375);
FORCEPROP 1 LAST PATH I27
J 0
(-1250 2425);
DISPLAY 0.978723 (-1250 2425);
PAINT WHITE (-1250 2425);
DISPLAY INVISIBLE (-1250 2425);
FORCEPROP 2 LAST CDS_LIB mstr_discrete
J 0
(-1300 2275);
PAINT ORANGE (-1300 2275);
DISPLAY INVISIBLE (-1300 2275);
FORCEADD CAP..1
(-1400 4350);
FORCEPROP 1 LASTPIN (-1400 4450) $PN 1
J 0
(-1390 4430);
DISPLAY 0.617021 (-1390 4430);
PAINT ORANGE (-1390 4430);
FORCEPROP 1 LAST TOLERANCE 10%
J 0
(-1350 4300);
DISPLAY 0.617021 (-1350 4300);
PAINT SKYBLUE (-1350 4300);
FORCEPROP 1 LAST VALUE 10UF
J 0
(-1350 4400);
DISPLAY 0.617021 (-1350 4400);
PAINT SKYBLUE (-1350 4400);
FORCEPROP 1 LAST LOCATION C1E21
J 0
(-1350 4450);
DISPLAY 0.617021 (-1350 4450);
PAINT AQUA (-1350 4450);
FORCEPROP 1 LAST VOLTAGE 16V
J 0
(-1350 4350);
DISPLAY 0.617021 (-1350 4350);
PAINT SKYBLUE (-1350 4350);
FORCEPROP 1 LASTPIN (-1400 4250) $PN 2
J 0
(-1390 4230);
DISPLAY 0.617021 (-1390 4230);
PAINT ORANGE (-1390 4230);
FORCEPROP 1 LAST PACK_TYPE 0805
J 0
(-1350 4150);
DISPLAY 0.617021 (-1350 4150);
PAINT SKYBLUE (-1350 4150);
FORCEPROP 1 LAST MATERIAL X6S
J 0
(-1350 4250);
DISPLAY 0.617021 (-1350 4250);
PAINT SKYBLUE (-1350 4250);
FORCEPROP 1 LAST PART_NUMBER C95333-007
J 0
(-1350 4200);
DISPLAY 0.617021 (-1350 4200);
PAINT BLUE (-1350 4200);
FORCEPROP 2 LAST CDS_LIB mstr_discrete
J 0
(-1400 4350);
PAINT ORANGE (-1400 4350);
DISPLAY INVISIBLE (-1400 4350);
FORCEPROP 0 LAST ROOM CPU_FANS
J 0
(-1350 4550);
DISPLAY 1.021277 (-1350 4550);
PAINT ORANGE (-1350 4550);
DISPLAY INVISIBLE (-1350 4550);
FORCEPROP 1 LAST PATH I3
J 0
(-1350 4500);
DISPLAY 0.978723 (-1350 4500);
PAINT WHITE (-1350 4500);
DISPLAY INVISIBLE (-1350 4500);
FORCEPROP 2 LAST CDS_LOCATION C1E21
J 0
(-1350 4450);
DISPLAY 0.617021 (-1350 4450);
PAINT AQUA (-1350 4450);
DISPLAY INVISIBLE (-1350 4450);
FORCEPROP 2 LAST SEC 1
J 0
(-1350 4550);
DISPLAY 0.680851 (-1350 4550);
PAINT MONO (-1350 4550);
DISPLAY INVISIBLE (-1350 4550);
FORCEPROP 0 LAST BOM_COST SM_THERM
J 0
(-1350 4500);
DISPLAY 1.021277 (-1350 4500);
PAINT ORANGE (-1350 4500);
DISPLAY INVISIBLE (-1350 4500);
FORCEPROP 2 LAST SEC_TYPE 0805
J 0
(-1350 4550);
DISPLAY 1.021277 (-1350 4550);
PAINT ORANGE (-1350 4550);
DISPLAY INVISIBLE (-1350 4550);
FORCEADD GND..1
(-1300 1950);
FORCEPROP 3 LASTPIN (-1300 2000) SIG_NAME GND\g
J 0
(-1290 2010);
DISPLAY 0.659574 (-1290 2010);
PAINT MONO (-1290 2010);
DISPLAY INVISIBLE (-1290 2010);
FORCEPROP 1 LAST HDL_POWER GND
J 0
(-1300 2100);
DISPLAY 1.170213 (-1300 2100);
PAINT GREEN (-1300 2100);
DISPLAY INVISIBLE (-1300 2100);
FORCEPROP 1 LAST SIZE 1B
J 0
(-1225 1900);
DISPLAY 1.170213 (-1225 1900);
PAINT AQUA (-1225 1900);
DISPLAY INVISIBLE (-1225 1900);
FORCEPROP 1 LAST PATH I30
J 0
(-1225 1950);
DISPLAY 0.872340 (-1225 1950);
PAINT AQUA (-1225 1950);
DISPLAY INVISIBLE (-1225 1950);
FORCEPROP 1 LAST VOLTAGE 0.0V
J 0
(-1345 1907);
DISPLAY 0.340426 (-1345 1907);
PAINT SKYBLUE (-1345 1907);
DISPLAY INVISIBLE (-1345 1907);
FORCEPROP 2 LAST CDS_LIB mstr_symbols
J 0
(-1300 1950);
PAINT ORANGE (-1300 1950);
DISPLAY INVISIBLE (-1300 1950);
FORCEPROP 1 LAST BODY_TYPE PLUMBING
J 0
(-1345 1907);
DISPLAY 0.340426 (-1345 1907);
PAINT GREEN (-1345 1907);
DISPLAY INVISIBLE (-1345 1907);
FORCEADD CAP_A..1
(-1125 4325);
FORCEPROP 1 LAST PART_NUMBER A36096-030
J 0
(-1075 4175);
DISPLAY 0.617021 (-1075 4175);
PAINT BLUE (-1075 4175);
FORCEPROP 1 LAST LOCATION C1E20
J 0
(-1075 4425);
DISPLAY 0.617021 (-1075 4425);
PAINT AQUA (-1075 4425);
FORCEPROP 1 LAST VALUE 0.1UF
J 0
(-1075 4375);
DISPLAY 0.617021 (-1075 4375);
PAINT SKYBLUE (-1075 4375);
FORCEPROP 1 LAST VOLTAGE 16V
J 0
(-1075 4325);
DISPLAY 0.617021 (-1075 4325);
PAINT SKYBLUE (-1075 4325);
FORCEPROP 1 LAST TOLERANCE 10%
J 0
(-1075 4275);
DISPLAY 0.617021 (-1075 4275);
PAINT SKYBLUE (-1075 4275);
FORCEPROP 1 LAST MATERIAL X7R
J 0
(-1075 4225);
DISPLAY 0.617021 (-1075 4225);
PAINT SKYBLUE (-1075 4225);
FORCEPROP 1 LAST PACK_TYPE 0402V
J 0
(-1075 4125);
DISPLAY 0.617021 (-1075 4125);
PAINT SKYBLUE (-1075 4125);
FORCEPROP 1 LASTPIN (-1125 4225) $PN 2
J 0
(-1115 4205);
DISPLAY 0.617021 (-1115 4205);
PAINT ORANGE (-1115 4205);
FORCEPROP 1 LASTPIN (-1125 4425) $PN 1
J 0
(-1115 4405);
DISPLAY 0.617021 (-1115 4405);
PAINT ORANGE (-1115 4405);
FORCEPROP 2 LAST CDS_LIB dev_discrete
J 0
(-1125 4325);
PAINT ORANGE (-1125 4325);
DISPLAY INVISIBLE (-1125 4325);
FORCEPROP 2 LAST SEC_TYPE 0402V
J 0
(-1075 4525);
DISPLAY 1.021277 (-1075 4525);
PAINT ORANGE (-1075 4525);
DISPLAY INVISIBLE (-1075 4525);
FORCEPROP 0 LAST ROOM CPU_FANS
J 0
(-1075 4525);
DISPLAY 1.021277 (-1075 4525);
PAINT ORANGE (-1075 4525);
DISPLAY INVISIBLE (-1075 4525);
FORCEPROP 2 LAST CDS_LOCATION C1E20
J 0
(-1075 4425);
DISPLAY 0.617021 (-1075 4425);
PAINT AQUA (-1075 4425);
DISPLAY INVISIBLE (-1075 4425);
FORCEPROP 2 LAST SEC 1
J 0
(-1075 4525);
DISPLAY 0.680851 (-1075 4525);
PAINT MONO (-1075 4525);
DISPLAY INVISIBLE (-1075 4525);
FORCEPROP 0 LAST BOM_COST SM_THERM
J 0
(-1075 4475);
DISPLAY 1.021277 (-1075 4475);
PAINT ORANGE (-1075 4475);
DISPLAY INVISIBLE (-1075 4475);
FORCEPROP 1 LAST PATH I4
J 0
(-1075 4475);
DISPLAY 0.978723 (-1075 4475);
PAINT WHITE (-1075 4475);
DISPLAY INVISIBLE (-1075 4475);
FORCEPROP 2 LAST CDS_SEC 1
J 0
(-1075 4475);
PAINT ORANGE (-1075 4475);
DISPLAY INVISIBLE (-1075 4475);
FORCEADD DIODE..1
(-1675 3825);
FORCEPROP 1 LAST VALUE SDMK0340L
J 0
(-1700 3700);
DISPLAY 0.617021 (-1700 3700);
PAINT SKYBLUE (-1700 3700);
FORCEPROP 1 LAST LOCATION CR1F1
J 0
(-1752 3981);
DISPLAY 0.617021 (-1752 3981);
PAINT AQUA (-1752 3981);
FORCEPROP 1 LAST PART_NUMBER H71799-001
J 0
(-1700 3925);
DISPLAY 0.617021 (-1700 3925);
PAINT BLUE (-1700 3925);
FORCEPROP 1 LAST MATERIAL IC
J 0
(-1700 3647);
DISPLAY 0.617021 (-1700 3647);
PAINT SKYBLUE (-1700 3647);
FORCEPROP 1 LAST PACK_TYPE SM
J 0
(-1700 3585);
DISPLAY 0.617021 (-1700 3585);
PAINT SKYBLUE (-1700 3585);
FORCEPROP 1 LASTPIN (-1775 3825) $PN 2
J 2
(-1740 3835);
DISPLAY 0.617021 (-1740 3835);
PAINT AQUA (-1740 3835);
FORCEPROP 1 LASTPIN (-1575 3825) $PN 1
J 0
(-1610 3835);
DISPLAY 0.617021 (-1610 3835);
PAINT AQUA (-1610 3835);
FORCEPROP 2 LAST CDS_LIB mstr_discrete
J 0
(-1675 3825);
PAINT ORANGE (-1675 3825);
DISPLAY INVISIBLE (-1675 3825);
FORCEPROP 2 LAST CDS_LOCATION CR1F1
J 0
(-1752 3981);
DISPLAY 0.617021 (-1752 3981);
PAINT AQUA (-1752 3981);
DISPLAY INVISIBLE (-1752 3981);
FORCEPROP 1 LAST PATH I42
J 0
(-1695 4035);
DISPLAY 0.978723 (-1695 4035);
PAINT PINK (-1695 4035);
DISPLAY INVISIBLE (-1695 4035);
FORCEPROP 0 LAST ROOM CPU_FANS
J 0
(-1700 4075);
DISPLAY 1.021277 (-1700 4075);
PAINT ORANGE (-1700 4075);
DISPLAY INVISIBLE (-1700 4075);
FORCEPROP 2 LAST SEC 1
J 0
(-1675 4100);
DISPLAY 0.680851 (-1675 4100);
PAINT MONO (-1675 4100);
DISPLAY INVISIBLE (-1675 4100);
FORCEPROP 2 LAST SEC_TYPE SM
J 0
(-1675 4100);
DISPLAY 1.021277 (-1675 4100);
PAINT ORANGE (-1675 4100);
DISPLAY INVISIBLE (-1675 4100);
FORCEPROP 0 LAST BOM_COST SM_THERM
J 0
(-1700 4175);
DISPLAY 1.021277 (-1700 4175);
PAINT ORANGE (-1700 4175);
DISPLAY INVISIBLE (-1700 4175);
FORCEADD RES..1
(-2525 3825);
FORCEPROP 1 LASTPIN (-2625 3825) $PN 1
J 0
(-2613 3837);
DISPLAY 0.617021 (-2613 3837);
PAINT ORANGE (-2613 3837);
FORCEPROP 1 LASTPIN (-2425 3825) $PN 2
J 0
(-2463 3837);
DISPLAY 0.617021 (-2463 3837);
PAINT ORANGE (-2463 3837);
FORCEPROP 1 LAST PACK_TYPE 0402
J 0
(-2425 3725);
DISPLAY 0.617021 (-2425 3725);
PAINT SKYBLUE (-2425 3725);
FORCEPROP 1 LAST LOCATION R1F2
J 0
(-2575 3875);
DISPLAY 0.617021 (-2575 3875);
PAINT AQUA (-2575 3875);
FORCEPROP 1 LAST WATTAGE 1/16W
J 2
(-2550 3675);
DISPLAY 0.617021 (-2550 3675);
PAINT SKYBLUE (-2550 3675);
FORCEPROP 1 LAST VALUE 100.0
J 2
(-2550 3725);
DISPLAY 0.617021 (-2550 3725);
PAINT SKYBLUE (-2550 3725);
FORCEPROP 1 LAST MATERIAL CHIP
J 0
(-2525 3675);
DISPLAY 0.617021 (-2525 3675);
PAINT SKYBLUE (-2525 3675);
FORCEPROP 1 LAST TOLERANCE 1%
J 0
(-2525 3725);
DISPLAY 0.617021 (-2525 3725);
PAINT SKYBLUE (-2525 3725);
FORCEPROP 1 LAST PART_NUMBER G21796-017
J 0
(-2575 3925);
DISPLAY 0.617021 (-2575 3925);
PAINT BLUE (-2575 3925);
FORCEPROP 2 LAST SEC_TYPE 0402
J 0
(-2575 4025);
DISPLAY 1.021277 (-2575 4025);
PAINT ORANGE (-2575 4025);
DISPLAY INVISIBLE (-2575 4025);
FORCEPROP 2 LAST SEC 1
J 0
(-2575 4025);
DISPLAY 0.680851 (-2575 4025);
PAINT MONO (-2575 4025);
DISPLAY INVISIBLE (-2575 4025);
FORCEPROP 2 LAST CDS_LOCATION R1F2
J 0
(-2575 3875);
DISPLAY 0.617021 (-2575 3875);
PAINT AQUA (-2575 3875);
DISPLAY INVISIBLE (-2575 3875);
FORCEPROP 2 LAST NO_XNET_CONNECTION 1
J 0
(-2575 4025);
PAINT MONO (-2575 4025);
DISPLAY INVISIBLE (-2575 4025);
FORCEPROP 1 LAST PATH I43
J 0
(-2575 3975);
DISPLAY 0.978723 (-2575 3975);
PAINT WHITE (-2575 3975);
DISPLAY INVISIBLE (-2575 3975);
FORCEPROP 0 LAST ROOM CPU_FANS
J 0
(-2575 4025);
DISPLAY 1.021277 (-2575 4025);
PAINT ORANGE (-2575 4025);
DISPLAY INVISIBLE (-2575 4025);
FORCEPROP 2 LAST CDS_LIB mstr_discrete
J 0
(-2525 3825);
PAINT ORANGE (-2525 3825);
DISPLAY INVISIBLE (-2525 3825);
FORCEPROP 0 LAST BOM_COST SM_THERM
J 0
(-2575 4125);
DISPLAY 1.021277 (-2575 4125);
PAINT ORANGE (-2575 4125);
DISPLAY INVISIBLE (-2575 4125);
FORCEADD RES..2
(-2900 4025);
FORCEPROP 1 LASTPIN (-2900 3925) $PN 2
J 0
(-2895 3935);
DISPLAY 0.617021 (-2895 3935);
PAINT ORANGE (-2895 3935);
FORCEPROP 1 LASTPIN (-2900 4125) $PN 1
J 0
(-2895 4087);
DISPLAY 0.617021 (-2895 4087);
PAINT ORANGE (-2895 4087);
FORCEPROP 1 LAST VALUE 4.75K
J 0
(-2855 4100);
DISPLAY 0.617021 (-2855 4100);
PAINT SKYBLUE (-2855 4100);
FORCEPROP 1 LAST LOCATION R1F1
J 0
(-2855 4150);
DISPLAY 0.617021 (-2855 4150);
PAINT AQUA (-2855 4150);
FORCEPROP 1 LAST WATTAGE 1/16W
J 0
(-2860 4000);
DISPLAY 0.617021 (-2860 4000);
PAINT SKYBLUE (-2860 4000);
FORCEPROP 1 LAST PACK_TYPE 0402
J 0
(-2860 3850);
DISPLAY 0.617021 (-2860 3850);
PAINT SKYBLUE (-2860 3850);
FORCEPROP 1 LAST MATERIAL CHIP
J 0
(-2860 3950);
DISPLAY 0.617021 (-2860 3950);
PAINT SKYBLUE (-2860 3950);
FORCEPROP 1 LAST PART_NUMBER G21796-072
J 0
(-2860 3900);
DISPLAY 0.617021 (-2860 3900);
PAINT BLUE (-2860 3900);
FORCEPROP 1 LAST TOLERANCE 1%
J 0
(-2855 4050);
DISPLAY 0.617021 (-2855 4050);
PAINT SKYBLUE (-2855 4050);
FORCEPROP 2 LAST CDS_LIB mstr_discrete
J 0
(-2900 4025);
PAINT ORANGE (-2900 4025);
DISPLAY INVISIBLE (-2900 4025);
FORCEPROP 2 LAST CDS_LOCATION R1F1
J 0
(-2855 4150);
DISPLAY 0.617021 (-2855 4150);
PAINT AQUA (-2855 4150);
DISPLAY INVISIBLE (-2855 4150);
FORCEPROP 1 LAST PATH I45
J 0
(-2850 4200);
DISPLAY 0.978723 (-2850 4200);
PAINT WHITE (-2850 4200);
DISPLAY INVISIBLE (-2850 4200);
FORCEPROP 0 LAST ROOM CPU_FANS
J 0
(-2850 4250);
DISPLAY 1.021277 (-2850 4250);
PAINT ORANGE (-2850 4250);
DISPLAY INVISIBLE (-2850 4250);
FORCEPROP 2 LAST SEC 1
J 0
(-2850 4250);
DISPLAY 0.680851 (-2850 4250);
PAINT MONO (-2850 4250);
DISPLAY INVISIBLE (-2850 4250);
FORCEPROP 2 LAST SEC_TYPE 0402
J 0
(-2850 4250);
DISPLAY 1.021277 (-2850 4250);
PAINT ORANGE (-2850 4250);
DISPLAY INVISIBLE (-2850 4250);
FORCEPROP 0 LAST BOM_COST SM_THERM
J 0
(-2850 4350);
DISPLAY 1.021277 (-2850 4350);
PAINT ORANGE (-2850 4350);
DISPLAY INVISIBLE (-2850 4350);
FORCEADD CAP_A..1
R 2
(-2775 3625);
FORCEPROP 1 LAST PART_NUMBER A36096-045
J 2
(-2825 3475);
DISPLAY 0.617021 (-2825 3475);
PAINT BLUE (-2825 3475);
FORCEPROP 1 LAST MATERIAL X7R
J 2
(-2825 3525);
DISPLAY 0.617021 (-2825 3525);
PAINT SKYBLUE (-2825 3525);
FORCEPROP 1 LAST PACK_TYPE 0402V
J 2
(-2825 3425);
DISPLAY 0.617021 (-2825 3425);
PAINT SKYBLUE (-2825 3425);
FORCEPROP 1 LASTPIN (-2775 3525) $PN 2
J 2
(-2785 3505);
DISPLAY 0.617021 (-2785 3505);
PAINT ORANGE (-2785 3505);
FORCEPROP 1 LAST TOLERANCE 10%
J 2
(-2825 3575);
DISPLAY 0.617021 (-2825 3575);
PAINT SKYBLUE (-2825 3575);
FORCEPROP 1 LAST LOCATION C1F9
J 2
(-2825 3725);
DISPLAY 0.617021 (-2825 3725);
PAINT AQUA (-2825 3725);
FORCEPROP 1 LASTPIN (-2775 3725) $PN 1
J 2
(-2785 3705);
DISPLAY 0.617021 (-2785 3705);
PAINT ORANGE (-2785 3705);
FORCEPROP 1 LAST VOLTAGE 25V
J 2
(-2825 3625);
DISPLAY 0.617021 (-2825 3625);
PAINT SKYBLUE (-2825 3625);
FORCEPROP 1 LAST VALUE 0.01UF
J 2
(-2825 3675);
DISPLAY 0.617021 (-2825 3675);
PAINT SKYBLUE (-2825 3675);
FORCEPROP 2 LAST CDS_SEC 1
J 0
(-2825 3775);
PAINT ORANGE (-2825 3775);
DISPLAY INVISIBLE (-2825 3775);
FORCEPROP 1 LAST PATH I46
J 2
(-2825 3775);
DISPLAY 0.978723 (-2825 3775);
PAINT WHITE (-2825 3775);
DISPLAY INVISIBLE (-2825 3775);
FORCEPROP 2 LAST CDS_LOCATION C1F9
J 2
(-2825 3725);
DISPLAY 0.617021 (-2825 3725);
PAINT AQUA (-2825 3725);
DISPLAY INVISIBLE (-2825 3725);
FORCEPROP 0 LAST BOM_COST SM_THERM
J 0
(-2825 3825);
DISPLAY 1.021277 (-2825 3825);
PAINT ORANGE (-2825 3825);
DISPLAY INVISIBLE (-2825 3825);
FORCEPROP 2 LAST SEC_TYPE 0402V
J 2
(-2825 3825);
DISPLAY 1.021277 (-2825 3825);
PAINT ORANGE (-2825 3825);
DISPLAY INVISIBLE (-2825 3825);
FORCEPROP 2 LAST SEC 1
J 2
(-2825 3825);
DISPLAY 0.680851 (-2825 3825);
PAINT MONO (-2825 3825);
DISPLAY INVISIBLE (-2825 3825);
FORCEPROP 0 LAST ROOM CPU_FANS
J 0
(-2825 3825);
DISPLAY 1.021277 (-2825 3825);
PAINT ORANGE (-2825 3825);
DISPLAY INVISIBLE (-2825 3825);
FORCEPROP 2 LAST CDS_LIB dev_discrete
J 0
(-2775 3625);
PAINT ORANGE (-2775 3625);
DISPLAY INVISIBLE (-2775 3625);
FORCEADD GND..1
(-2775 3375);
FORCEPROP 3 LASTPIN (-2775 3425) SIG_NAME GND\g
J 0
(-2765 3435);
DISPLAY 0.659574 (-2765 3435);
PAINT MONO (-2765 3435);
DISPLAY INVISIBLE (-2765 3435);
FORCEPROP 1 LAST VOLTAGE 0.0V
J 0
(-2820 3332);
DISPLAY 0.340426 (-2820 3332);
PAINT SKYBLUE (-2820 3332);
DISPLAY INVISIBLE (-2820 3332);
FORCEPROP 1 LAST BODY_TYPE PLUMBING
J 0
(-2820 3332);
DISPLAY 0.340426 (-2820 3332);
PAINT GREEN (-2820 3332);
DISPLAY INVISIBLE (-2820 3332);
FORCEPROP 1 LAST SIZE 1B
J 0
(-2700 3325);
DISPLAY 1.170213 (-2700 3325);
PAINT AQUA (-2700 3325);
DISPLAY INVISIBLE (-2700 3325);
FORCEPROP 1 LAST HDL_POWER GND
J 0
(-2775 3525);
DISPLAY 1.170213 (-2775 3525);
PAINT GREEN (-2775 3525);
DISPLAY INVISIBLE (-2775 3525);
FORCEPROP 1 LAST PATH I47
J 0
(-2700 3375);
DISPLAY 0.872340 (-2700 3375);
PAINT AQUA (-2700 3375);
DISPLAY INVISIBLE (-2700 3375);
FORCEPROP 2 LAST CDS_LIB mstr_symbols
J 0
(-2775 3375);
PAINT ORANGE (-2775 3375);
DISPLAY INVISIBLE (-2775 3375);
FORCEADD P3V3_STBY..1
(-2900 4250);
FORCEPROP 3 LASTPIN (-2900 4200) SIG_NAME P3V3_STBY\g
J 0
(-2890 4210);
DISPLAY 0.659574 (-2890 4210);
PAINT MONO (-2890 4210);
DISPLAY INVISIBLE (-2890 4210);
FORCEPROP 1 LAST HDL_POWER P3V3_STBY
J 0
(-3200 4125);
DISPLAY 0.872340 (-3200 4125);
PAINT ORANGE (-3200 4125);
DISPLAY INVISIBLE (-3200 4125);
FORCEPROP 1 LAST BODY_TYPE PLUMBING
J 0
(-2945 4207);
DISPLAY 0.340426 (-2945 4207);
PAINT GREEN (-2945 4207);
DISPLAY INVISIBLE (-2945 4207);
FORCEPROP 1 LAST VOLTAGE 3.3V
J 0
(-2945 4207);
DISPLAY 0.340426 (-2945 4207);
PAINT SKYBLUE (-2945 4207);
DISPLAY INVISIBLE (-2945 4207);
FORCEPROP 2 LAST CDS_LIB mstr_symbols
J 0
(-2900 4250);
PAINT ORANGE (-2900 4250);
DISPLAY INVISIBLE (-2900 4250);
FORCEPROP 1 LAST SIZE 1B
J 0
(-2855 4272);
DISPLAY 0.340426 (-2855 4272);
PAINT GREEN (-2855 4272);
DISPLAY INVISIBLE (-2855 4272);
FORCEPROP 1 LAST PATH I48
J 0
(-2855 4252);
DISPLAY 0.340426 (-2855 4252);
PAINT GREEN (-2855 4252);
DISPLAY INVISIBLE (-2855 4252);
FORCEADD OFFPAGE..2
R 2
(-3650 3825);
FORCEPROP 2 LAST $XR1 147 
J 0
(-4025 3825);
DISPLAY 0.638298 (-4025 3825);
PAINT MONO (-4025 3825);
FORCEPROP 2 LAST $XR0 181 
J 0
(-3905 3825);
DISPLAY 0.638298 (-3905 3825);
PAINT MONO (-3905 3825);
FORCEPROP 1 LAST OFFPAGE TRUE
J 2
(-3975 3700);
DISPLAY 0.872340 (-3975 3700);
PAINT GREEN (-3975 3700);
DISPLAY INVISIBLE (-3975 3700);
FORCEPROP 1 LAST COMMENT_BODY TRUE
J 2
(-3605 3730);
DISPLAY 0.872340 (-3605 3730);
PAINT GREEN (-3605 3730);
DISPLAY INVISIBLE (-3605 3730);
FORCEPROP 2 LAST CDS_LIB mstr_standard
J 2
(-3650 3825);
PAINT ORANGE (-3650 3825);
DISPLAY INVISIBLE (-3650 3825);
FORCEPROP 2 LAST PATH I49
J 2
(-3700 3900);
DISPLAY 1.021277 (-3700 3900);
PAINT ORANGE (-3700 3900);
DISPLAY INVISIBLE (-3700 3900);
FORCEADD DIODE..4
(-1950 3325);
FORCEPROP 1 LAST VALUE SDMK0340L
J 0
(-1850 3375);
DISPLAY 0.617021 (-1850 3375);
PAINT SKYBLUE (-1850 3375);
FORCEPROP 1 LAST MATERIAL EMPTY
J 0
(-1848 3309);
DISPLAY 0.617021 (-1848 3309);
PAINT RED (-1848 3309);
FORCEPROP 1 LAST LOCATION CR1E1
J 0
(-1850 3430);
DISPLAY 0.617021 (-1850 3430);
PAINT AQUA (-1850 3430);
FORCEPROP 1 LASTPIN (-1950 3225) $PN 2
J 0
(-1935 3225);
DISPLAY 0.617021 (-1935 3225);
PAINT AQUA (-1935 3225);
FORCEPROP 1 LASTPIN (-1950 3425) $PN 1
J 0
(-1935 3395);
DISPLAY 0.617021 (-1935 3395);
PAINT AQUA (-1935 3395);
FORCEPROP 1 LAST PACK_TYPE SM
J 0
(-1849 3198);
DISPLAY 0.617021 (-1849 3198);
PAINT SKYBLUE (-1849 3198);
FORCEPROP 1 LAST PART_NUMBER H71799-001
J 0
(-1850 3250);
DISPLAY 0.617021 (-1850 3250);
PAINT BLUE (-1850 3250);
FORCEPROP 2 LAST CDS_LIB mstr_discrete
J 0
(-1950 3325);
PAINT ORANGE (-1950 3325);
DISPLAY INVISIBLE (-1950 3325);
FORCEPROP 0 LAST ROOM CPU_FANS
J 0
(-1850 3525);
DISPLAY 1.021277 (-1850 3525);
PAINT ORANGE (-1850 3525);
DISPLAY INVISIBLE (-1850 3525);
FORCEPROP 1 LAST PATH I50
J 0
(-1845 3490);
DISPLAY 0.978723 (-1845 3490);
PAINT PINK (-1845 3490);
DISPLAY INVISIBLE (-1845 3490);
FORCEPROP 2 LAST CDS_LOCATION CR1E1
J 0
(-1850 3430);
DISPLAY 0.617021 (-1850 3430);
PAINT AQUA (-1850 3430);
DISPLAY INVISIBLE (-1850 3430);
FORCEPROP 2 LAST SEC 1
J 0
(-1825 3550);
DISPLAY 0.680851 (-1825 3550);
PAINT MONO (-1825 3550);
DISPLAY INVISIBLE (-1825 3550);
FORCEPROP 2 LAST SEC_TYPE SM
J 0
(-1825 3550);
DISPLAY 1.021277 (-1825 3550);
PAINT ORANGE (-1825 3550);
DISPLAY INVISIBLE (-1825 3550);
FORCEPROP 0 LAST BOM_COST SM_THERM
J 0
(-1850 3625);
DISPLAY 1.021277 (-1850 3625);
PAINT ORANGE (-1850 3625);
DISPLAY INVISIBLE (-1850 3625);
FORCEADD RES..2
R 2
(-2175 3400);
FORCEPROP 1 LAST WATTAGE 1/16W
J 2
(-2215 3375);
DISPLAY 0.617021 (-2215 3375);
PAINT SKYBLUE (-2215 3375);
FORCEPROP 1 LAST MATERIAL CHIP
J 2
(-2215 3325);
DISPLAY 0.617021 (-2215 3325);
PAINT SKYBLUE (-2215 3325);
FORCEPROP 1 LAST LOCATION R1E12
J 2
(-2220 3525);
DISPLAY 0.617021 (-2220 3525);
PAINT AQUA (-2220 3525);
FORCEPROP 1 LAST VALUE 4.75K
J 2
(-2220 3475);
DISPLAY 0.617021 (-2220 3475);
PAINT SKYBLUE (-2220 3475);
FORCEPROP 1 LASTPIN (-2175 3300) $PN 2
J 2
(-2180 3310);
DISPLAY 0.617021 (-2180 3310);
PAINT ORANGE (-2180 3310);
FORCEPROP 1 LASTPIN (-2175 3500) $PN 1
J 2
(-2180 3462);
DISPLAY 0.617021 (-2180 3462);
PAINT ORANGE (-2180 3462);
FORCEPROP 1 LAST TOLERANCE 1%
J 2
(-2220 3425);
DISPLAY 0.617021 (-2220 3425);
PAINT SKYBLUE (-2220 3425);
FORCEPROP 1 LAST PART_NUMBER G21796-072
J 2
(-2215 3275);
DISPLAY 0.617021 (-2215 3275);
PAINT BLUE (-2215 3275);
FORCEPROP 1 LAST PACK_TYPE 0402
J 2
(-2215 3225);
DISPLAY 0.617021 (-2215 3225);
PAINT SKYBLUE (-2215 3225);
FORCEPROP 2 LAST CDS_LOCATION R1E12
J 2
(-2220 3525);
DISPLAY 0.617021 (-2220 3525);
PAINT AQUA (-2220 3525);
DISPLAY INVISIBLE (-2220 3525);
FORCEPROP 2 LAST CDS_LIB mstr_discrete
J 0
(-2175 3400);
PAINT MONO (-2175 3400);
DISPLAY INVISIBLE (-2175 3400);
FORCEPROP 1 LAST PATH I51
J 2
(-2225 3575);
DISPLAY 0.978723 (-2225 3575);
PAINT WHITE (-2225 3575);
DISPLAY INVISIBLE (-2225 3575);
FORCEPROP 2 LAST SEC_TYPE 0402
J 0
(-2225 3625);
DISPLAY 1.021277 (-2225 3625);
PAINT ORANGE (-2225 3625);
DISPLAY INVISIBLE (-2225 3625);
FORCEPROP 0 LAST BOM_COST SM_THERM
J 0
(-2200 3725);
DISPLAY 1.021277 (-2200 3725);
PAINT ORANGE (-2200 3725);
DISPLAY INVISIBLE (-2200 3725);
FORCEPROP 2 LAST SEC 1
J 0
(-2225 3625);
PAINT MONO (-2225 3625);
DISPLAY INVISIBLE (-2225 3625);
FORCEPROP 0 LAST ROOM CPU_FANS
J 0
(-2200 3625);
DISPLAY 1.021277 (-2200 3625);
PAINT ORANGE (-2200 3625);
DISPLAY INVISIBLE (-2200 3625);
FORCEADD P5V_STBY..1
(-1950 3625);
FORCEPROP 3 LASTPIN (-1950 3575) SIG_NAME P5V_STBY\g
J 0
(-1940 3585);
DISPLAY 0.659574 (-1940 3585);
PAINT MONO (-1940 3585);
DISPLAY INVISIBLE (-1940 3585);
FORCEPROP 1 LAST HDL_POWER P5V_STBY
J 0
(-2250 3500);
DISPLAY 0.872340 (-2250 3500);
PAINT ORANGE (-2250 3500);
DISPLAY INVISIBLE (-2250 3500);
FORCEPROP 1 LAST BODY_TYPE PLUMBING
J 0
(-1995 3582);
DISPLAY 0.340426 (-1995 3582);
PAINT GREEN (-1995 3582);
DISPLAY INVISIBLE (-1995 3582);
FORCEPROP 1 LAST VOLTAGE 5.0V
J 0
(-1995 3582);
DISPLAY 0.340426 (-1995 3582);
PAINT SKYBLUE (-1995 3582);
DISPLAY INVISIBLE (-1995 3582);
FORCEPROP 1 LAST SIZE 1B
J 0
(-1905 3647);
DISPLAY 0.340426 (-1905 3647);
PAINT GREEN (-1905 3647);
DISPLAY INVISIBLE (-1905 3647);
FORCEPROP 2 LAST CDS_LIB mstr_symbols
J 0
(-1950 3625);
PAINT ORANGE (-1950 3625);
DISPLAY INVISIBLE (-1950 3625);
FORCEPROP 1 LAST PATH I52
J 0
(-1905 3627);
DISPLAY 0.340426 (-1905 3627);
PAINT GREEN (-1905 3627);
DISPLAY INVISIBLE (-1905 3627);
FORCEADD OFFPAGE..1
(-3625 3225);
FORCEPROP 2 LAST $XR1 181 
J 0
(-3997 3225);
DISPLAY 0.638298 (-3997 3225);
PAINT MONO (-3997 3225);
FORCEPROP 2 LAST $XR0 161 
J 0
(-3877 3225);
DISPLAY 0.638298 (-3877 3225);
PAINT MONO (-3877 3225);
FORCEPROP 2 LAST CDS_LIB mstr_standard
J 0
(-3625 3225);
PAINT ORANGE (-3625 3225);
DISPLAY INVISIBLE (-3625 3225);
FORCEPROP 2 LAST PATH I53
J 0
(-3575 3300);
DISPLAY 1.021277 (-3575 3300);
PAINT ORANGE (-3575 3300);
DISPLAY INVISIBLE (-3575 3300);
FORCEPROP 1 LAST COMMENT_BODY TRUE
J 0
(-3500 3125);
DISPLAY 1.170213 (-3500 3125);
PAINT PEACH (-3500 3125);
DISPLAY INVISIBLE (-3500 3125);
FORCEPROP 1 LAST OFFPAGE TRUE
J 0
(-3300 3100);
DISPLAY 1.170213 (-3300 3100);
PAINT GREEN (-3300 3100);
DISPLAY INVISIBLE (-3300 3100);
FORCEADD P3V3_STBY..1
(-3050 2175);
FORCEPROP 3 LASTPIN (-3050 2125) SIG_NAME P3V3_STBY\g
J 0
(-3040 2135);
DISPLAY 0.659574 (-3040 2135);
PAINT MONO (-3040 2135);
DISPLAY INVISIBLE (-3040 2135);
FORCEPROP 1 LAST SIZE 1B
J 0
(-3005 2197);
DISPLAY 0.340426 (-3005 2197);
PAINT GREEN (-3005 2197);
DISPLAY INVISIBLE (-3005 2197);
FORCEPROP 1 LAST PATH I61
J 0
(-3005 2177);
DISPLAY 0.340426 (-3005 2177);
PAINT GREEN (-3005 2177);
DISPLAY INVISIBLE (-3005 2177);
FORCEPROP 2 LAST CDS_LIB mstr_symbols
J 0
(-3050 2175);
PAINT ORANGE (-3050 2175);
DISPLAY INVISIBLE (-3050 2175);
FORCEPROP 1 LAST VOLTAGE 3.3V
J 0
(-3095 2132);
DISPLAY 0.340426 (-3095 2132);
PAINT SKYBLUE (-3095 2132);
DISPLAY INVISIBLE (-3095 2132);
FORCEPROP 1 LAST BODY_TYPE PLUMBING
J 0
(-3095 2132);
DISPLAY 0.340426 (-3095 2132);
PAINT GREEN (-3095 2132);
DISPLAY INVISIBLE (-3095 2132);
FORCEPROP 1 LAST HDL_POWER P3V3_STBY
J 0
(-3350 2050);
DISPLAY 0.872340 (-3350 2050);
PAINT ORANGE (-3350 2050);
DISPLAY INVISIBLE (-3350 2050);
FORCEADD DIODE..1
(-1825 1750);
FORCEPROP 1 LAST VALUE SDMK0340L
J 0
(-1850 1625);
DISPLAY 0.617021 (-1850 1625);
PAINT SKYBLUE (-1850 1625);
FORCEPROP 1 LAST PACK_TYPE SM
J 0
(-1850 1510);
DISPLAY 0.617021 (-1850 1510);
PAINT SKYBLUE (-1850 1510);
FORCEPROP 1 LASTPIN (-1725 1750) $PN 1
J 0
(-1760 1760);
DISPLAY 0.617021 (-1760 1760);
PAINT AQUA (-1760 1760);
FORCEPROP 1 LAST LOCATION CR1B2
J 0
(-1852 1906);
DISPLAY 0.617021 (-1852 1906);
PAINT AQUA (-1852 1906);
FORCEPROP 1 LASTPIN (-1925 1750) $PN 2
J 2
(-1890 1760);
DISPLAY 0.617021 (-1890 1760);
PAINT AQUA (-1890 1760);
FORCEPROP 1 LAST PART_NUMBER H71799-001
J 0
(-1850 1850);
DISPLAY 0.617021 (-1850 1850);
PAINT BLUE (-1850 1850);
FORCEPROP 1 LAST MATERIAL IC
J 0
(-1850 1572);
DISPLAY 0.617021 (-1850 1572);
PAINT SKYBLUE (-1850 1572);
FORCEPROP 0 LAST BOM_COST SM_THERM
J 0
(-1850 2100);
DISPLAY 1.021277 (-1850 2100);
PAINT ORANGE (-1850 2100);
DISPLAY INVISIBLE (-1850 2100);
FORCEPROP 2 LAST SEC_TYPE SM
J 0
(-1825 2025);
DISPLAY 1.021277 (-1825 2025);
PAINT ORANGE (-1825 2025);
DISPLAY INVISIBLE (-1825 2025);
FORCEPROP 2 LAST SEC 1
J 0
(-1825 2025);
DISPLAY 0.680851 (-1825 2025);
PAINT MONO (-1825 2025);
DISPLAY INVISIBLE (-1825 2025);
FORCEPROP 0 LAST ROOM CPU_FANS
J 0
(-1850 2000);
DISPLAY 1.021277 (-1850 2000);
PAINT ORANGE (-1850 2000);
DISPLAY INVISIBLE (-1850 2000);
FORCEPROP 1 LAST PATH I62
J 0
(-1845 1960);
DISPLAY 0.978723 (-1845 1960);
PAINT PINK (-1845 1960);
DISPLAY INVISIBLE (-1845 1960);
FORCEPROP 2 LAST CDS_LOCATION CR1B2
J 0
(-1852 1906);
DISPLAY 0.617021 (-1852 1906);
PAINT AQUA (-1852 1906);
DISPLAY INVISIBLE (-1852 1906);
FORCEPROP 2 LAST CDS_LIB mstr_discrete
J 0
(-1825 1750);
PAINT ORANGE (-1825 1750);
DISPLAY INVISIBLE (-1825 1750);
FORCEADD P5V_STBY..1
(-2100 1550);
FORCEPROP 3 LASTPIN (-2100 1500) SIG_NAME P5V_STBY\g
J 0
(-2090 1510);
DISPLAY 0.659574 (-2090 1510);
PAINT MONO (-2090 1510);
DISPLAY INVISIBLE (-2090 1510);
FORCEPROP 1 LAST SIZE 1B
J 0
(-2055 1572);
DISPLAY 0.340426 (-2055 1572);
PAINT GREEN (-2055 1572);
DISPLAY INVISIBLE (-2055 1572);
FORCEPROP 2 LAST CDS_LIB mstr_symbols
J 0
(-2100 1550);
PAINT ORANGE (-2100 1550);
DISPLAY INVISIBLE (-2100 1550);
FORCEPROP 1 LAST PATH I63
J 0
(-2055 1552);
DISPLAY 0.340426 (-2055 1552);
PAINT GREEN (-2055 1552);
DISPLAY INVISIBLE (-2055 1552);
FORCEPROP 1 LAST VOLTAGE 5.0V
J 0
(-2145 1507);
DISPLAY 0.340426 (-2145 1507);
PAINT SKYBLUE (-2145 1507);
DISPLAY INVISIBLE (-2145 1507);
FORCEPROP 1 LAST BODY_TYPE PLUMBING
J 0
(-2145 1507);
DISPLAY 0.340426 (-2145 1507);
PAINT GREEN (-2145 1507);
DISPLAY INVISIBLE (-2145 1507);
FORCEPROP 1 LAST HDL_POWER P5V_STBY
J 0
(-2400 1425);
DISPLAY 0.872340 (-2400 1425);
PAINT ORANGE (-2400 1425);
DISPLAY INVISIBLE (-2400 1425);
FORCEADD DIODE..4
(-2100 1250);
FORCEPROP 1 LAST VALUE SDMK0340L
J 0
(-2000 1300);
DISPLAY 0.617021 (-2000 1300);
PAINT SKYBLUE (-2000 1300);
FORCEPROP 1 LAST MATERIAL EMPTY
J 0
(-1998 1234);
DISPLAY 0.617021 (-1998 1234);
PAINT RED (-1998 1234);
FORCEPROP 1 LAST PART_NUMBER H71799-001
J 0
(-2000 1175);
DISPLAY 0.617021 (-2000 1175);
PAINT BLUE (-2000 1175);
FORCEPROP 1 LAST LOCATION CR1B1
J 0
(-2000 1355);
DISPLAY 0.617021 (-2000 1355);
PAINT AQUA (-2000 1355);
FORCEPROP 1 LASTPIN (-2100 1150) $PN 2
J 0
(-2085 1150);
DISPLAY 0.617021 (-2085 1150);
PAINT AQUA (-2085 1150);
FORCEPROP 1 LAST PACK_TYPE SM
J 0
(-1999 1123);
DISPLAY 0.617021 (-1999 1123);
PAINT SKYBLUE (-1999 1123);
FORCEPROP 1 LASTPIN (-2100 1350) $PN 1
J 0
(-2085 1320);
DISPLAY 0.617021 (-2085 1320);
PAINT AQUA (-2085 1320);
FORCEPROP 0 LAST BOM_COST SM_THERM
J 0
(-2000 1550);
DISPLAY 1.021277 (-2000 1550);
PAINT ORANGE (-2000 1550);
DISPLAY INVISIBLE (-2000 1550);
FORCEPROP 2 LAST SEC_TYPE SM
J 0
(-1975 1475);
DISPLAY 1.021277 (-1975 1475);
PAINT ORANGE (-1975 1475);
DISPLAY INVISIBLE (-1975 1475);
FORCEPROP 2 LAST SEC 1
J 0
(-1975 1475);
DISPLAY 0.680851 (-1975 1475);
PAINT MONO (-1975 1475);
DISPLAY INVISIBLE (-1975 1475);
FORCEPROP 2 LAST CDS_LOCATION CR1B1
J 0
(-2000 1355);
DISPLAY 0.617021 (-2000 1355);
PAINT AQUA (-2000 1355);
DISPLAY INVISIBLE (-2000 1355);
FORCEPROP 1 LAST PATH I64
J 0
(-1995 1415);
DISPLAY 0.978723 (-1995 1415);
PAINT PINK (-1995 1415);
DISPLAY INVISIBLE (-1995 1415);
FORCEPROP 0 LAST ROOM CPU_FANS
J 0
(-2000 1450);
DISPLAY 1.021277 (-2000 1450);
PAINT ORANGE (-2000 1450);
DISPLAY INVISIBLE (-2000 1450);
FORCEPROP 2 LAST CDS_LIB mstr_discrete
J 0
(-2100 1250);
PAINT ORANGE (-2100 1250);
DISPLAY INVISIBLE (-2100 1250);
FORCEADD RES..2
R 2
(-2325 1300);
FORCEPROP 1 LAST PACK_TYPE 0402
J 2
(-2365 1125);
DISPLAY 0.617021 (-2365 1125);
PAINT SKYBLUE (-2365 1125);
FORCEPROP 1 LAST LOCATION R7F33
J 2
(-2370 1425);
DISPLAY 0.617021 (-2370 1425);
PAINT AQUA (-2370 1425);
FORCEPROP 1 LAST MATERIAL CHIP
J 2
(-2365 1225);
DISPLAY 0.617021 (-2365 1225);
PAINT SKYBLUE (-2365 1225);
FORCEPROP 1 LAST WATTAGE 1/16W
J 2
(-2365 1275);
DISPLAY 0.617021 (-2365 1275);
PAINT SKYBLUE (-2365 1275);
FORCEPROP 1 LAST TOLERANCE 1%
J 2
(-2370 1325);
DISPLAY 0.617021 (-2370 1325);
PAINT SKYBLUE (-2370 1325);
FORCEPROP 1 LAST VALUE 4.75K
J 2
(-2370 1375);
DISPLAY 0.617021 (-2370 1375);
PAINT SKYBLUE (-2370 1375);
FORCEPROP 1 LASTPIN (-2325 1400) $PN 1
J 2
(-2330 1362);
DISPLAY 0.617021 (-2330 1362);
PAINT ORANGE (-2330 1362);
FORCEPROP 1 LASTPIN (-2325 1200) $PN 2
J 2
(-2330 1210);
DISPLAY 0.617021 (-2330 1210);
PAINT ORANGE (-2330 1210);
FORCEPROP 1 LAST PART_NUMBER G21796-072
J 2
(-2365 1175);
DISPLAY 0.617021 (-2365 1175);
PAINT BLUE (-2365 1175);
FORCEPROP 0 LAST BOM_COST SM_THERM
J 0
(-2350 1625);
DISPLAY 1.021277 (-2350 1625);
PAINT ORANGE (-2350 1625);
DISPLAY INVISIBLE (-2350 1625);
FORCEPROP 2 LAST SEC_TYPE 0402
J 0
(-2375 1525);
DISPLAY 1.021277 (-2375 1525);
PAINT ORANGE (-2375 1525);
DISPLAY INVISIBLE (-2375 1525);
FORCEPROP 2 LAST SEC 1
J 0
(-2375 1525);
PAINT MONO (-2375 1525);
DISPLAY INVISIBLE (-2375 1525);
FORCEPROP 0 LAST ROOM CPU_FANS
J 0
(-2350 1525);
DISPLAY 1.021277 (-2350 1525);
PAINT ORANGE (-2350 1525);
DISPLAY INVISIBLE (-2350 1525);
FORCEPROP 1 LAST PATH I65
J 2
(-2375 1475);
DISPLAY 0.978723 (-2375 1475);
PAINT WHITE (-2375 1475);
DISPLAY INVISIBLE (-2375 1475);
FORCEPROP 2 LAST CDS_LOCATION R7F33
J 2
(-2370 1425);
DISPLAY 0.617021 (-2370 1425);
PAINT AQUA (-2370 1425);
DISPLAY INVISIBLE (-2370 1425);
FORCEPROP 2 LAST CDS_LIB mstr_discrete
J 0
(-2325 1300);
PAINT MONO (-2325 1300);
DISPLAY INVISIBLE (-2325 1300);
FORCEADD RES..1
(-2675 1750);
FORCEPROP 1 LAST WATTAGE 1/16W
J 2
(-2700 1600);
DISPLAY 0.617021 (-2700 1600);
PAINT SKYBLUE (-2700 1600);
FORCEPROP 1 LAST VALUE 100.0
J 2
(-2700 1650);
DISPLAY 0.617021 (-2700 1650);
PAINT SKYBLUE (-2700 1650);
FORCEPROP 1 LAST PACK_TYPE 0402
J 0
(-2575 1650);
DISPLAY 0.617021 (-2575 1650);
PAINT SKYBLUE (-2575 1650);
FORCEPROP 1 LASTPIN (-2575 1750) $PN 2
J 0
(-2613 1762);
DISPLAY 0.617021 (-2613 1762);
PAINT ORANGE (-2613 1762);
FORCEPROP 1 LASTPIN (-2775 1750) $PN 1
J 0
(-2763 1762);
DISPLAY 0.617021 (-2763 1762);
PAINT ORANGE (-2763 1762);
FORCEPROP 1 LAST MATERIAL CHIP
J 0
(-2675 1600);
DISPLAY 0.617021 (-2675 1600);
PAINT SKYBLUE (-2675 1600);
FORCEPROP 1 LAST TOLERANCE 1%
J 0
(-2675 1650);
DISPLAY 0.617021 (-2675 1650);
PAINT SKYBLUE (-2675 1650);
FORCEPROP 1 LAST LOCATION R1B22
J 0
(-2725 1800);
DISPLAY 0.617021 (-2725 1800);
PAINT AQUA (-2725 1800);
FORCEPROP 1 LAST PART_NUMBER G21796-017
J 0
(-2725 1850);
DISPLAY 0.617021 (-2725 1850);
PAINT BLUE (-2725 1850);
FORCEPROP 0 LAST BOM_COST SM_THERM
J 0
(-2725 2050);
DISPLAY 1.021277 (-2725 2050);
PAINT ORANGE (-2725 2050);
DISPLAY INVISIBLE (-2725 2050);
FORCEPROP 2 LAST CDS_LOCATION R1B22
J 0
(-2725 1800);
DISPLAY 0.617021 (-2725 1800);
PAINT AQUA (-2725 1800);
DISPLAY INVISIBLE (-2725 1800);
FORCEPROP 2 LAST SEC 1
J 0
(-2725 1950);
DISPLAY 0.680851 (-2725 1950);
PAINT MONO (-2725 1950);
DISPLAY INVISIBLE (-2725 1950);
FORCEPROP 2 LAST SEC_TYPE 0402
J 0
(-2725 1950);
DISPLAY 1.021277 (-2725 1950);
PAINT ORANGE (-2725 1950);
DISPLAY INVISIBLE (-2725 1950);
FORCEPROP 2 LAST NO_XNET_CONNECTION 1
J 0
(-2725 1950);
PAINT MONO (-2725 1950);
DISPLAY INVISIBLE (-2725 1950);
FORCEPROP 1 LAST PATH I67
J 0
(-2725 1900);
DISPLAY 0.978723 (-2725 1900);
PAINT WHITE (-2725 1900);
DISPLAY INVISIBLE (-2725 1900);
FORCEPROP 0 LAST ROOM CPU_FANS
J 0
(-2725 1950);
DISPLAY 1.021277 (-2725 1950);
PAINT ORANGE (-2725 1950);
DISPLAY INVISIBLE (-2725 1950);
FORCEPROP 2 LAST CDS_LIB mstr_discrete
J 0
(-2675 1750);
PAINT ORANGE (-2675 1750);
DISPLAY INVISIBLE (-2675 1750);
FORCEADD CAP_A..1
R 2
(-2925 1550);
FORCEPROP 1 LAST PART_NUMBER A36096-045
J 2
(-2975 1400);
DISPLAY 0.617021 (-2975 1400);
PAINT BLUE (-2975 1400);
FORCEPROP 1 LAST VALUE 0.01UF
J 2
(-2975 1600);
DISPLAY 0.617021 (-2975 1600);
PAINT SKYBLUE (-2975 1600);
FORCEPROP 1 LAST LOCATION C1B15
J 2
(-2975 1650);
DISPLAY 0.617021 (-2975 1650);
PAINT AQUA (-2975 1650);
FORCEPROP 1 LASTPIN (-2925 1650) $PN 1
J 2
(-2935 1630);
DISPLAY 0.617021 (-2935 1630);
PAINT ORANGE (-2935 1630);
FORCEPROP 1 LAST MATERIAL X7R
J 2
(-2975 1450);
DISPLAY 0.617021 (-2975 1450);
PAINT SKYBLUE (-2975 1450);
FORCEPROP 1 LAST PACK_TYPE 0402V
J 2
(-2975 1350);
DISPLAY 0.617021 (-2975 1350);
PAINT SKYBLUE (-2975 1350);
FORCEPROP 1 LAST TOLERANCE 10%
J 2
(-2975 1500);
DISPLAY 0.617021 (-2975 1500);
PAINT SKYBLUE (-2975 1500);
FORCEPROP 1 LASTPIN (-2925 1450) $PN 2
J 2
(-2935 1430);
DISPLAY 0.617021 (-2935 1430);
PAINT ORANGE (-2935 1430);
FORCEPROP 1 LAST VOLTAGE 25V
J 2
(-2975 1550);
DISPLAY 0.617021 (-2975 1550);
PAINT SKYBLUE (-2975 1550);
FORCEPROP 2 LAST CDS_LOCATION C1B15
J 2
(-2725 1550);
DISPLAY 0.617021 (-2725 1550);
PAINT AQUA (-2725 1550);
DISPLAY INVISIBLE (-2725 1550);
FORCEPROP 2 LAST SEC_TYPE 0402V
J 2
(-2975 1750);
DISPLAY 1.021277 (-2975 1750);
PAINT ORANGE (-2975 1750);
DISPLAY INVISIBLE (-2975 1750);
FORCEPROP 2 LAST CDS_LIB dev_discrete
J 0
(-2925 1550);
PAINT ORANGE (-2925 1550);
DISPLAY INVISIBLE (-2925 1550);
FORCEPROP 0 LAST ROOM CPU_FANS
J 0
(-2975 1700);
DISPLAY 1.021277 (-2975 1700);
PAINT ORANGE (-2975 1700);
DISPLAY INVISIBLE (-2975 1700);
FORCEPROP 1 LAST PATH I68
J 2
(-2975 1700);
DISPLAY 0.978723 (-2975 1700);
PAINT WHITE (-2975 1700);
DISPLAY INVISIBLE (-2975 1700);
FORCEPROP 2 LAST SEC 1
J 2
(-2975 1750);
DISPLAY 0.680851 (-2975 1750);
PAINT MONO (-2975 1750);
DISPLAY INVISIBLE (-2975 1750);
FORCEPROP 2 LAST CDS_SEC 1
J 0
(-2975 1650);
PAINT ORANGE (-2975 1650);
DISPLAY INVISIBLE (-2975 1650);
FORCEPROP 0 LAST BOM_COST SM_THERM
J 0
(-2975 1700);
DISPLAY 1.021277 (-2975 1700);
PAINT ORANGE (-2975 1700);
DISPLAY INVISIBLE (-2975 1700);
FORCEADD GND..1
(-2925 1300);
FORCEPROP 3 LASTPIN (-2925 1350) SIG_NAME GND\g
J 0
(-2915 1360);
DISPLAY 0.659574 (-2915 1360);
PAINT MONO (-2915 1360);
DISPLAY INVISIBLE (-2915 1360);
FORCEPROP 1 LAST HDL_POWER GND
J 0
(-2925 1450);
DISPLAY 1.170213 (-2925 1450);
PAINT GREEN (-2925 1450);
DISPLAY INVISIBLE (-2925 1450);
FORCEPROP 1 LAST PATH I69
J 0
(-2850 1300);
DISPLAY 0.872340 (-2850 1300);
PAINT AQUA (-2850 1300);
DISPLAY INVISIBLE (-2850 1300);
FORCEPROP 2 LAST CDS_LIB mstr_symbols
J 0
(-2925 1300);
PAINT ORANGE (-2925 1300);
DISPLAY INVISIBLE (-2925 1300);
FORCEPROP 1 LAST SIZE 1B
J 0
(-2850 1250);
DISPLAY 1.170213 (-2850 1250);
PAINT AQUA (-2850 1250);
DISPLAY INVISIBLE (-2850 1250);
FORCEPROP 1 LAST VOLTAGE 0.0V
J 0
(-2970 1257);
DISPLAY 0.340426 (-2970 1257);
PAINT SKYBLUE (-2970 1257);
DISPLAY INVISIBLE (-2970 1257);
FORCEPROP 1 LAST BODY_TYPE PLUMBING
J 0
(-2970 1257);
DISPLAY 0.340426 (-2970 1257);
PAINT GREEN (-2970 1257);
DISPLAY INVISIBLE (-2970 1257);
FORCEADD RES..2
(-3050 1950);
FORCEPROP 1 LAST PART_NUMBER G21796-072
J 0
(-3010 1825);
DISPLAY 0.617021 (-3010 1825);
PAINT BLUE (-3010 1825);
FORCEPROP 1 LAST VALUE 4.75K
J 0
(-3005 2025);
DISPLAY 0.617021 (-3005 2025);
PAINT SKYBLUE (-3005 2025);
FORCEPROP 1 LASTPIN (-3050 2050) $PN 1
J 0
(-3045 2012);
DISPLAY 0.617021 (-3045 2012);
PAINT ORANGE (-3045 2012);
FORCEPROP 1 LASTPIN (-3050 1850) $PN 2
J 0
(-3045 1860);
DISPLAY 0.617021 (-3045 1860);
PAINT ORANGE (-3045 1860);
FORCEPROP 1 LAST TOLERANCE 1%
J 0
(-3005 1975);
DISPLAY 0.617021 (-3005 1975);
PAINT SKYBLUE (-3005 1975);
FORCEPROP 1 LAST MATERIAL CHIP
J 0
(-3010 1875);
DISPLAY 0.617021 (-3010 1875);
PAINT SKYBLUE (-3010 1875);
FORCEPROP 1 LAST PACK_TYPE 0402
J 0
(-3010 1775);
DISPLAY 0.617021 (-3010 1775);
PAINT SKYBLUE (-3010 1775);
FORCEPROP 1 LAST LOCATION R1B21
J 0
(-3005 2075);
DISPLAY 0.617021 (-3005 2075);
PAINT AQUA (-3005 2075);
FORCEPROP 1 LAST WATTAGE 1/16W
J 0
(-3010 1925);
DISPLAY 0.617021 (-3010 1925);
PAINT SKYBLUE (-3010 1925);
FORCEPROP 0 LAST BOM_COST SM_THERM
J 0
(-3000 2275);
DISPLAY 1.021277 (-3000 2275);
PAINT ORANGE (-3000 2275);
DISPLAY INVISIBLE (-3000 2275);
FORCEPROP 2 LAST SEC_TYPE 0402
J 0
(-3000 2175);
DISPLAY 1.021277 (-3000 2175);
PAINT ORANGE (-3000 2175);
DISPLAY INVISIBLE (-3000 2175);
FORCEPROP 2 LAST SEC 1
J 0
(-3000 2175);
DISPLAY 0.680851 (-3000 2175);
PAINT MONO (-3000 2175);
DISPLAY INVISIBLE (-3000 2175);
FORCEPROP 0 LAST ROOM CPU_FANS
J 0
(-3000 2175);
DISPLAY 1.021277 (-3000 2175);
PAINT ORANGE (-3000 2175);
DISPLAY INVISIBLE (-3000 2175);
FORCEPROP 2 LAST CDS_LOCATION R1B21
J 0
(-3005 2075);
DISPLAY 0.617021 (-3005 2075);
PAINT AQUA (-3005 2075);
DISPLAY INVISIBLE (-3005 2075);
FORCEPROP 1 LAST PATH I70
J 0
(-3000 2125);
DISPLAY 0.978723 (-3000 2125);
PAINT WHITE (-3000 2125);
DISPLAY INVISIBLE (-3000 2125);
FORCEPROP 2 LAST CDS_LIB mstr_discrete
J 0
(-3050 1950);
PAINT ORANGE (-3050 1950);
DISPLAY INVISIBLE (-3050 1950);
FORCEADD OFFPAGE..2
R 2
(-3600 1750);
FORCEPROP 2 LAST $XR1 147 
J 0
(-4005 1750);
DISPLAY 0.638298 (-4005 1750);
PAINT MONO (-4005 1750);
FORCEPROP 2 LAST $XR0 181 
J 0
(-3885 1750);
DISPLAY 0.638298 (-3885 1750);
PAINT MONO (-3885 1750);
FORCEPROP 2 LAST CDS_LIB mstr_standard
J 2
(-3600 1750);
PAINT ORANGE (-3600 1750);
DISPLAY INVISIBLE (-3600 1750);
FORCEPROP 2 LAST PATH I75
J 0
(-3550 1825);
DISPLAY 1.021277 (-3550 1825);
PAINT ORANGE (-3550 1825);
DISPLAY INVISIBLE (-3550 1825);
FORCEPROP 1 LAST OFFPAGE TRUE
J 2
(-3925 1625);
DISPLAY 0.872340 (-3925 1625);
PAINT GREEN (-3925 1625);
DISPLAY INVISIBLE (-3925 1625);
FORCEPROP 1 LAST COMMENT_BODY TRUE
J 2
(-3555 1655);
DISPLAY 0.872340 (-3555 1655);
PAINT GREEN (-3555 1655);
DISPLAY INVISIBLE (-3555 1655);
FORCEADD OFFPAGE..1
(-3600 1075);
FORCEPROP 2 LAST $XR0 161 
J 0
(-3852 1075);
DISPLAY 0.638298 (-3852 1075);
PAINT MONO (-3852 1075);
FORCEPROP 1 LAST OFFPAGE TRUE
J 0
(-3275 950);
DISPLAY 1.170213 (-3275 950);
PAINT GREEN (-3275 950);
DISPLAY INVISIBLE (-3275 950);
FORCEPROP 2 LAST CDS_LIB mstr_standard
J 0
(-3600 1075);
PAINT ORANGE (-3600 1075);
DISPLAY INVISIBLE (-3600 1075);
FORCEPROP 2 LAST PATH I76
J 0
(-3550 1150);
DISPLAY 1.021277 (-3550 1150);
PAINT ORANGE (-3550 1150);
DISPLAY INVISIBLE (-3550 1150);
FORCEPROP 1 LAST COMMENT_BODY TRUE
J 0
(-3475 975);
DISPLAY 1.170213 (-3475 975);
PAINT PEACH (-3475 975);
DISPLAY INVISIBLE (-3475 975);
FORCEADD TTL1G07_A..1
(-6350 3850);
FORCEPROP 2 LASTPIN (-6450 3850) $PN 2
J 2
(-6460 3860);
DISPLAY 0.617021 (-6460 3860);
PAINT ORANGE (-6460 3860);
FORCEPROP 1 LAST VALUE 74LVC1G07
J 1
(-6350 3950);
DISPLAY 0.617021 (-6350 3950);
PAINT SKYBLUE (-6350 3950);
FORCEPROP 1 LAST LOCATION U8G2
J 0
(-6450 4000);
DISPLAY 0.617021 (-6450 4000);
PAINT AQUA (-6450 4000);
FORCEPROP 1 LAST MATERIAL IC
J 0
(-6325 4000);
DISPLAY 0.617021 (-6325 4000);
PAINT SKYBLUE (-6325 4000);
FORCEPROP 2 LASTPIN (-6200 3850) $PN 4
J 0
(-6190 3860);
DISPLAY 0.617021 (-6190 3860);
PAINT ORANGE (-6190 3860);
FORCEPROP 1 LAST PART_NUMBER C88419-001
J 0
(-6400 3715);
DISPLAY 0.617021 (-6400 3715);
PAINT BLUE (-6400 3715);
FORCEPROP 1 LAST POWER_GROUP VCC=P3V3_STBY;GND=GND
J 1
(-6400 3660);
DISPLAY 0.617021 (-6400 3660);
PAINT ORANGE (-6400 3660);
FORCEPROP 2 LAST CDS_LOCATION U8G2
J 0
(-6450 4000);
DISPLAY 0.617021 (-6450 4000);
PAINT AQUA (-6450 4000);
DISPLAY INVISIBLE (-6450 4000);
FORCEPROP 2 LAST CDS_LIB mstr_ttl
J 0
(-6350 3850);
PAINT ORANGE (-6350 3850);
DISPLAY INVISIBLE (-6350 3850);
FORCEPROP 1 LAST PATH I88
J 0
(-6300 3900);
DISPLAY 0.978723 (-6300 3900);
PAINT WHITE (-6300 3900);
DISPLAY INVISIBLE (-6300 3900);
FORCEPROP 0 LAST ROOM CPU_FANS
J 0
(-6400 4150);
DISPLAY 1.021277 (-6400 4150);
PAINT ORANGE (-6400 4150);
DISPLAY INVISIBLE (-6400 4150);
FORCEPROP 2 LAST SEC 1
J 0
(-6400 4100);
DISPLAY 0.680851 (-6400 4100);
PAINT MONO (-6400 4100);
DISPLAY INVISIBLE (-6400 4100);
FORCEPROP 2 LAST SEC_TYPE SOP
J 0
(-6400 4100);
DISPLAY 1.021277 (-6400 4100);
PAINT ORANGE (-6400 4100);
DISPLAY INVISIBLE (-6400 4100);
FORCEPROP 0 LAST BOM_COST SM_THERM
J 0
(-6400 4250);
DISPLAY 1.021277 (-6400 4250);
PAINT ORANGE (-6400 4250);
DISPLAY INVISIBLE (-6400 4250);
FORCEPROP 1 LAST PACK_TYPE SOP
J 0
(-6400 4100);
DISPLAY 0.978723 (-6400 4100);
PAINT SKYBLUE (-6400 4100);
DISPLAY INVISIBLE (-6400 4100);
FORCEADD CAP_A..1
(-6300 4450);
FORCEPROP 1 LASTPIN (-6300 4350) $PN 2
J 0
(-6290 4330);
DISPLAY 0.617021 (-6290 4330);
PAINT ORANGE (-6290 4330);
FORCEPROP 1 LASTPIN (-6300 4550) $PN 1
J 0
(-6290 4530);
DISPLAY 0.617021 (-6290 4530);
PAINT ORANGE (-6290 4530);
FORCEPROP 1 LAST VOLTAGE 16V
J 0
(-6250 4450);
DISPLAY 0.617021 (-6250 4450);
PAINT SKYBLUE (-6250 4450);
FORCEPROP 1 LAST PACK_TYPE 0402V
J 0
(-6250 4250);
DISPLAY 0.617021 (-6250 4250);
PAINT SKYBLUE (-6250 4250);
FORCEPROP 1 LAST LOCATION C2U27
J 0
(-6250 4550);
DISPLAY 0.617021 (-6250 4550);
PAINT AQUA (-6250 4550);
FORCEPROP 1 LAST VALUE 0.1UF
J 0
(-6250 4500);
DISPLAY 0.617021 (-6250 4500);
PAINT SKYBLUE (-6250 4500);
FORCEPROP 1 LAST TOLERANCE 10%
J 0
(-6250 4400);
DISPLAY 0.617021 (-6250 4400);
PAINT SKYBLUE (-6250 4400);
FORCEPROP 1 LAST MATERIAL X7R
J 0
(-6250 4350);
DISPLAY 0.617021 (-6250 4350);
PAINT SKYBLUE (-6250 4350);
FORCEPROP 1 LAST PART_NUMBER A36096-030
J 0
(-6250 4300);
DISPLAY 0.617021 (-6250 4300);
PAINT BLUE (-6250 4300);
FORCEPROP 2 LAST CDS_LIB dev_discrete
J 0
(-6300 4450);
PAINT ORANGE (-6300 4450);
DISPLAY INVISIBLE (-6300 4450);
FORCEPROP 2 LAST CDS_LOCATION C2U27
J 0
(-6250 4550);
DISPLAY 0.617021 (-6250 4550);
PAINT AQUA (-6250 4550);
DISPLAY INVISIBLE (-6250 4550);
FORCEPROP 2 LAST CDS_SEC 1
J 0
(-6250 4600);
PAINT ORANGE (-6250 4600);
DISPLAY INVISIBLE (-6250 4600);
FORCEPROP 1 LAST PATH I90
J 0
(-6250 4600);
DISPLAY 0.978723 (-6250 4600);
PAINT WHITE (-6250 4600);
DISPLAY INVISIBLE (-6250 4600);
FORCEPROP 2 LAST SEC 1
J 0
(-6250 4650);
DISPLAY 0.680851 (-6250 4650);
PAINT MONO (-6250 4650);
DISPLAY INVISIBLE (-6250 4650);
FORCEPROP 2 LAST SEC_TYPE 0402V
J 0
(-6250 4650);
DISPLAY 1.021277 (-6250 4650);
PAINT ORANGE (-6250 4650);
DISPLAY INVISIBLE (-6250 4650);
FORCEPROP 0 LAST BOM_COST SM_THERM
J 0
(-6250 4750);
DISPLAY 1.021277 (-6250 4750);
PAINT ORANGE (-6250 4750);
DISPLAY INVISIBLE (-6250 4750);
FORCEPROP 0 LAST ROOM CPU_FANS
J 0
(-6250 4650);
DISPLAY 1.021277 (-6250 4650);
PAINT ORANGE (-6250 4650);
DISPLAY INVISIBLE (-6250 4650);
FORCEADD TTL1G07_A..1
(-6425 1100);
FORCEPROP 1 LAST PART_NUMBER C88419-001
J 0
(-6300 1165);
DISPLAY 0.617021 (-6300 1165);
PAINT BLUE (-6300 1165);
FORCEPROP 1 LAST MATERIAL IC
J 0
(-6375 1250);
DISPLAY 0.617021 (-6375 1250);
PAINT SKYBLUE (-6375 1250);
FORCEPROP 1 LAST VALUE 74LVC1G07
J 1
(-6425 1200);
DISPLAY 0.617021 (-6425 1200);
PAINT SKYBLUE (-6425 1200);
FORCEPROP 1 LAST LOCATION U8G3
J 0
(-6525 1250);
DISPLAY 0.617021 (-6525 1250);
PAINT AQUA (-6525 1250);
FORCEPROP 1 LAST POWER_GROUP VCC=P3V3_STBY;GND=GND
J 1
(-6800 1010);
DISPLAY 0.617021 (-6800 1010);
PAINT ORANGE (-6800 1010);
FORCEPROP 2 LASTPIN (-6275 1100) $PN 4
J 0
(-6265 1110);
DISPLAY 0.617021 (-6265 1110);
PAINT ORANGE (-6265 1110);
FORCEPROP 2 LASTPIN (-6525 1100) $PN 2
J 2
(-6535 1110);
DISPLAY 0.617021 (-6535 1110);
PAINT ORANGE (-6535 1110);
FORCEPROP 0 LAST BOM_COST SM_THERM
J 0
(-6475 1500);
DISPLAY 1.021277 (-6475 1500);
PAINT ORANGE (-6475 1500);
DISPLAY INVISIBLE (-6475 1500);
FORCEPROP 0 LAST ROOM CPU_FANS
J 0
(-6475 1400);
DISPLAY 1.021277 (-6475 1400);
PAINT ORANGE (-6475 1400);
DISPLAY INVISIBLE (-6475 1400);
FORCEPROP 1 LAST PACK_TYPE SOP
J 0
(-6475 1350);
DISPLAY 0.978723 (-6475 1350);
PAINT SKYBLUE (-6475 1350);
DISPLAY INVISIBLE (-6475 1350);
FORCEPROP 1 LAST PATH I92
J 0
(-6375 1150);
DISPLAY 0.978723 (-6375 1150);
PAINT WHITE (-6375 1150);
DISPLAY INVISIBLE (-6375 1150);
FORCEPROP 2 LAST SEC 1
J 0
(-6475 1350);
DISPLAY 0.680851 (-6475 1350);
PAINT MONO (-6475 1350);
DISPLAY INVISIBLE (-6475 1350);
FORCEPROP 2 LAST SEC_TYPE SOP
J 0
(-6475 1350);
DISPLAY 1.021277 (-6475 1350);
PAINT ORANGE (-6475 1350);
DISPLAY INVISIBLE (-6475 1350);
FORCEPROP 2 LAST CDS_LOCATION U8G3
J 0
(-6525 1250);
DISPLAY 0.617021 (-6525 1250);
PAINT AQUA (-6525 1250);
DISPLAY INVISIBLE (-6525 1250);
FORCEPROP 2 LAST CDS_LIB mstr_ttl
J 0
(-6425 1100);
PAINT ORANGE (-6425 1100);
DISPLAY INVISIBLE (-6425 1100);
FORCEADD CAP_A..1
(-6200 675);
FORCEPROP 1 LAST VALUE 0.1UF
J 0
(-6150 725);
DISPLAY 0.617021 (-6150 725);
PAINT SKYBLUE (-6150 725);
FORCEPROP 1 LAST LOCATION C2U28
J 0
(-6150 775);
DISPLAY 0.617021 (-6150 775);
PAINT AQUA (-6150 775);
FORCEPROP 1 LAST PART_NUMBER A36096-030
J 0
(-6150 525);
DISPLAY 0.617021 (-6150 525);
PAINT BLUE (-6150 525);
FORCEPROP 1 LAST TOLERANCE 10%
J 0
(-6150 625);
DISPLAY 0.617021 (-6150 625);
PAINT SKYBLUE (-6150 625);
FORCEPROP 1 LAST PACK_TYPE 0402V
J 0
(-6150 475);
DISPLAY 0.617021 (-6150 475);
PAINT SKYBLUE (-6150 475);
FORCEPROP 1 LAST VOLTAGE 16V
J 0
(-6150 675);
DISPLAY 0.617021 (-6150 675);
PAINT SKYBLUE (-6150 675);
FORCEPROP 1 LAST MATERIAL X7R
J 0
(-6150 575);
DISPLAY 0.617021 (-6150 575);
PAINT SKYBLUE (-6150 575);
FORCEPROP 1 LASTPIN (-6200 775) $PN 1
J 0
(-6190 755);
DISPLAY 0.617021 (-6190 755);
PAINT ORANGE (-6190 755);
FORCEPROP 1 LASTPIN (-6200 575) $PN 2
J 0
(-6190 555);
DISPLAY 0.617021 (-6190 555);
PAINT ORANGE (-6190 555);
FORCEPROP 0 LAST BOM_COST SM_THERM
J 0
(-6150 975);
DISPLAY 1.021277 (-6150 975);
PAINT ORANGE (-6150 975);
DISPLAY INVISIBLE (-6150 975);
FORCEPROP 0 LAST ROOM CPU_FANS
J 0
(-6150 875);
DISPLAY 1.021277 (-6150 875);
PAINT ORANGE (-6150 875);
DISPLAY INVISIBLE (-6150 875);
FORCEPROP 1 LAST PATH I93
J 0
(-6150 825);
DISPLAY 0.978723 (-6150 825);
PAINT WHITE (-6150 825);
DISPLAY INVISIBLE (-6150 825);
FORCEPROP 2 LAST SEC_TYPE 0402V
J 0
(-6150 875);
DISPLAY 1.021277 (-6150 875);
PAINT ORANGE (-6150 875);
DISPLAY INVISIBLE (-6150 875);
FORCEPROP 2 LAST SEC 1
J 0
(-6150 875);
DISPLAY 0.680851 (-6150 875);
PAINT MONO (-6150 875);
DISPLAY INVISIBLE (-6150 875);
FORCEPROP 2 LAST CDS_SEC 1
J 0
(-6150 825);
PAINT ORANGE (-6150 825);
DISPLAY INVISIBLE (-6150 825);
FORCEPROP 2 LAST CDS_LOCATION C2U28
J 0
(-6150 775);
DISPLAY 0.617021 (-6150 775);
PAINT AQUA (-6150 775);
DISPLAY INVISIBLE (-6150 775);
FORCEPROP 2 LAST CDS_LIB dev_discrete
J 0
(-6200 675);
PAINT ORANGE (-6200 675);
DISPLAY INVISIBLE (-6200 675);
FORCEADD OFFPAGE..1
(-7250 3850);
FORCEPROP 2 LAST $XR0 147 
J 0
(-7502 3850);
DISPLAY 0.638298 (-7502 3850);
PAINT MONO (-7502 3850);
FORCEPROP 2 LAST PATH I94
J 0
(-7200 3925);
DISPLAY 1.021277 (-7200 3925);
PAINT ORANGE (-7200 3925);
DISPLAY INVISIBLE (-7200 3925);
FORCEPROP 2 LAST CDS_LIB mstr_standard
J 0
(-7250 3850);
PAINT ORANGE (-7250 3850);
DISPLAY INVISIBLE (-7250 3850);
FORCEPROP 1 LAST OFFPAGE TRUE
J 0
(-6925 3725);
DISPLAY 1.170213 (-6925 3725);
PAINT GREEN (-6925 3725);
DISPLAY INVISIBLE (-6925 3725);
FORCEPROP 1 LAST COMMENT_BODY TRUE
J 0
(-7125 3750);
DISPLAY 1.170213 (-7125 3750);
PAINT PEACH (-7125 3750);
DISPLAY INVISIBLE (-7125 3750);
FORCEADD P3V3_STBY..1
(-6300 4650);
FORCEPROP 3 LASTPIN (-6300 4600) SIG_NAME P3V3_STBY\g
J 0
(-6290 4610);
DISPLAY 0.659574 (-6290 4610);
PAINT MONO (-6290 4610);
DISPLAY INVISIBLE (-6290 4610);
FORCEPROP 1 LAST HDL_POWER P3V3_STBY
J 0
(-6600 4525);
DISPLAY 0.872340 (-6600 4525);
PAINT ORANGE (-6600 4525);
DISPLAY INVISIBLE (-6600 4525);
FORCEPROP 1 LAST BODY_TYPE PLUMBING
J 0
(-6345 4607);
DISPLAY 0.340426 (-6345 4607);
PAINT GREEN (-6345 4607);
DISPLAY INVISIBLE (-6345 4607);
FORCEPROP 1 LAST VOLTAGE 3.3V
J 0
(-6345 4607);
DISPLAY 0.340426 (-6345 4607);
PAINT SKYBLUE (-6345 4607);
DISPLAY INVISIBLE (-6345 4607);
FORCEPROP 1 LAST PATH I96
J 0
(-6255 4652);
DISPLAY 0.340426 (-6255 4652);
PAINT GREEN (-6255 4652);
DISPLAY INVISIBLE (-6255 4652);
FORCEPROP 1 LAST SIZE 1B
J 0
(-6255 4672);
DISPLAY 0.340426 (-6255 4672);
PAINT GREEN (-6255 4672);
DISPLAY INVISIBLE (-6255 4672);
FORCEPROP 2 LAST CDS_LIB mstr_symbols
J 0
(-6300 4650);
PAINT ORANGE (-6300 4650);
DISPLAY INVISIBLE (-6300 4650);
FORCEADD GND..1
(-6300 4250);
FORCEPROP 3 LASTPIN (-6300 4300) SIG_NAME GND\g
J 0
(-6290 4310);
DISPLAY 0.659574 (-6290 4310);
PAINT MONO (-6290 4310);
DISPLAY INVISIBLE (-6290 4310);
FORCEPROP 1 LAST VOLTAGE 0.0V
J 0
(-6345 4207);
DISPLAY 0.340426 (-6345 4207);
PAINT SKYBLUE (-6345 4207);
DISPLAY INVISIBLE (-6345 4207);
FORCEPROP 2 LAST CDS_LIB mstr_symbols
J 0
(-6300 4250);
PAINT ORANGE (-6300 4250);
DISPLAY INVISIBLE (-6300 4250);
FORCEPROP 1 LAST BODY_TYPE PLUMBING
J 0
(-6345 4207);
DISPLAY 0.340426 (-6345 4207);
PAINT GREEN (-6345 4207);
DISPLAY INVISIBLE (-6345 4207);
FORCEPROP 1 LAST SIZE 1B
J 0
(-6225 4200);
DISPLAY 1.170213 (-6225 4200);
PAINT AQUA (-6225 4200);
DISPLAY INVISIBLE (-6225 4200);
FORCEPROP 1 LAST PATH I97
J 0
(-6225 4250);
DISPLAY 0.872340 (-6225 4250);
PAINT AQUA (-6225 4250);
DISPLAY INVISIBLE (-6225 4250);
FORCEPROP 1 LAST HDL_POWER GND
J 0
(-6300 4400);
DISPLAY 1.170213 (-6300 4400);
PAINT GREEN (-6300 4400);
DISPLAY INVISIBLE (-6300 4400);
FORCEADD OFFPAGE..2
(-4800 3850);
FORCEPROP 2 LAST $XR1 181 
J 0
(-4491 3850);
DISPLAY 0.638298 (-4491 3850);
PAINT MONO (-4491 3850);
FORCEPROP 2 LAST $XR0 161 
J 0
(-4611 3850);
DISPLAY 0.638298 (-4611 3850);
PAINT MONO (-4611 3850);
FORCEPROP 1 LAST COMMENT_BODY TRUE
J 0
(-4845 3755);
DISPLAY 0.872340 (-4845 3755);
PAINT GREEN (-4845 3755);
DISPLAY INVISIBLE (-4845 3755);
FORCEPROP 2 LAST PATH I98
J 2
(-4850 3925);
DISPLAY 1.021277 (-4850 3925);
PAINT ORANGE (-4850 3925);
DISPLAY INVISIBLE (-4850 3925);
FORCEPROP 2 LAST CDS_LIB mstr_standard
J 2
(-4800 3850);
PAINT ORANGE (-4800 3850);
DISPLAY INVISIBLE (-4800 3850);
FORCEPROP 1 LAST OFFPAGE TRUE
J 0
(-4475 3725);
DISPLAY 0.872340 (-4475 3725);
PAINT GREEN (-4475 3725);
DISPLAY INVISIBLE (-4475 3725);
FORCEADD RES..1
(-5450 3850);
FORCEPROP 1 LAST VALUE 221
J 2
(-5475 3750);
DISPLAY 0.617021 (-5475 3750);
PAINT SKYBLUE (-5475 3750);
FORCEPROP 1 LAST WATTAGE 1/16W
J 2
(-5475 3700);
DISPLAY 0.617021 (-5475 3700);
PAINT SKYBLUE (-5475 3700);
FORCEPROP 1 LASTPIN (-5550 3850) $PN 1
J 0
(-5538 3862);
DISPLAY 0.617021 (-5538 3862);
PAINT ORANGE (-5538 3862);
FORCEPROP 1 LAST PART_NUMBER G21796-271
J 0
(-5500 3950);
DISPLAY 0.617021 (-5500 3950);
PAINT BLUE (-5500 3950);
FORCEPROP 1 LAST LOCATION R2U42
J 0
(-5500 3900);
DISPLAY 0.617021 (-5500 3900);
PAINT AQUA (-5500 3900);
FORCEPROP 1 LASTPIN (-5350 3850) $PN 2
J 0
(-5388 3862);
DISPLAY 0.617021 (-5388 3862);
PAINT ORANGE (-5388 3862);
FORCEPROP 1 LAST TOLERANCE 1.0%
J 0
(-5450 3750);
DISPLAY 0.617021 (-5450 3750);
PAINT SKYBLUE (-5450 3750);
FORCEPROP 1 LAST MATERIAL CHIP
J 0
(-5450 3700);
DISPLAY 0.617021 (-5450 3700);
PAINT SKYBLUE (-5450 3700);
FORCEPROP 1 LAST PACK_TYPE 0402
J 0
(-5300 3700);
DISPLAY 0.617021 (-5300 3700);
PAINT SKYBLUE (-5300 3700);
FORCEPROP 2 LAST CDS_LOCATION R2U42
J 0
(-5500 3900);
DISPLAY 0.617021 (-5500 3900);
PAINT AQUA (-5500 3900);
DISPLAY INVISIBLE (-5500 3900);
FORCEPROP 2 LAST SEC 1
J 0
(-5500 4050);
DISPLAY 0.680851 (-5500 4050);
PAINT MONO (-5500 4050);
DISPLAY INVISIBLE (-5500 4050);
FORCEPROP 2 LAST CDS_LIB mstr_discrete
J 0
(-5450 3850);
PAINT ORANGE (-5450 3850);
DISPLAY INVISIBLE (-5450 3850);
FORCEPROP 2 LAST SEC_TYPE 0402
J 0
(-5500 4050);
DISPLAY 1.021277 (-5500 4050);
PAINT ORANGE (-5500 4050);
DISPLAY INVISIBLE (-5500 4050);
FORCEPROP 1 LAST PATH I99
J 0
(-5500 4000);
DISPLAY 0.978723 (-5500 4000);
PAINT WHITE (-5500 4000);
DISPLAY INVISIBLE (-5500 4000);
FORCEPROP 0 LAST ROOM CPU_FANS
J 0
(-5500 4050);
DISPLAY 1.021277 (-5500 4050);
PAINT ORANGE (-5500 4050);
DISPLAY INVISIBLE (-5500 4050);
FORCEPROP 0 LAST BOM_COST SM_THERM
J 0
(-5500 4150);
DISPLAY 1.021277 (-5500 4150);
PAINT ORANGE (-5500 4150);
DISPLAY INVISIBLE (-5500 4150);
FORCEADD CAD_NOTE..1
(-5725 700);
FORCEPROP 0 LAST L1 PLACE CAP CLOSE
J 0
(-5875 575);
DISPLAY 0.617021 (-5875 575);
PAINT WHITE (-5875 575);
FORCEPROP 0 LAST L2 TO IC
J 0
(-5875 500);
DISPLAY 0.617021 (-5875 500);
PAINT WHITE (-5875 500);
FORCEPROP 1 LAST COMMENT_BODY TRUE
J 0
(-5700 800);
DISPLAY 1.361702 (-5700 800);
PAINT WHITE (-5700 800);
DISPLAY INVISIBLE (-5700 800);
FORCEPROP 2 LAST CDS_LIB mstr_symbols
J 0
(-5725 700);
PAINT ORANGE (-5725 700);
DISPLAY INVISIBLE (-5725 700);
FORCEADD INTEL_CORP_BPAGE..1
(-25 25);
FORCEPROP 1 LAST CDS_CON_LAST_MODIFIED Fri Jun 16 17:49:00 2017
J 0
(-1450 350);
DISPLAY 1.361702 (-1450 350);
PAINT GREEN (-1450 350);
DISPLAY INVISIBLE (-1450 350);
FORCEPROP 1 LAST CUSTOM_TXT_CDS <CURRENT_DESIGN_SHEET> OF <TOTAL_DESIGN_SHEETS>
J 0
(-525 50);
PAINT ORANGE (-525 50);
FORCEPROP 1 LAST CUSTOM_TXT_CDS <CON_LAST_MODIFIED>
J 0
(-4025 125);
PAINT ORANGE (-4025 125);
FORCEPROP 2 LAST CUSTOM_TXT_CDS <XR_PAGE_TITLE>
J 0
(-7915 5275);
DISPLAY 0.638298 (-7915 5275);
PAINT PINK (-7915 5275);
DISPLAY INVISIBLE (-7915 5275);
FORCEPROP 1 LAST SCH_TITLE FAN HEADERS
J 0
(-7975 75);
DISPLAY 1.212766 (-7975 75);
PAINT ORANGE (-7975 75);
FORCEPROP 2 LAST CDS_LIB mstr_symbols
J 0
(-25 25);
DISPLAY 1.361702 (-25 25);
PAINT ORANGE (-25 25);
DISPLAY INVISIBLE (-25 25);
FORCEPROP 1 LAST COMMENT_BODY TRUE
J 0
(-13 37);
DISPLAY 0.617021 (-13 37);
PAINT GREEN (-13 37);
DISPLAY INVISIBLE (-13 37);
FORCEPROP 2 LAST PAGE_BORDER TRUE
J 0
(-7915 5275);
DISPLAY 0.851064 (-7915 5275);
PAINT PINK (-7915 5275);
DISPLAY INVISIBLE (-7915 5275);
FORCEPROP 2 LAST CDS_XR_PAGE_TITLE CR-161 : @BASEBOARD_FAB2_LIB.BASEBOARD_FAB2(SCH_1):PAGE161
J 0
(-7915 5275);
DISPLAY 0.638298 (-7915 5275);
PAINT PINK (-7915 5275);
DISPLAY INVISIBLE (-7915 5275);
FORCEADD CAD_NOTE..1
(-5825 4475);
FORCEPROP 0 LAST L2 TO IC
J 0
(-5975 4275);
DISPLAY 0.617021 (-5975 4275);
PAINT WHITE (-5975 4275);
FORCEPROP 0 LAST L1 PLACE CAP CLOSE
J 0
(-5975 4350);
DISPLAY 0.617021 (-5975 4350);
PAINT WHITE (-5975 4350);
FORCEPROP 1 LAST COMMENT_BODY TRUE
J 0
(-5800 4575);
DISPLAY 1.361702 (-5800 4575);
PAINT WHITE (-5800 4575);
DISPLAY INVISIBLE (-5800 4575);
FORCEPROP 2 LAST CDS_LIB mstr_symbols
J 0
(-5825 4475);
PAINT ORANGE (-5825 4475);
DISPLAY INVISIBLE (-5825 4475);
FORCEADD DNS..2
(-1945 3320);
PAINT RED (-1945 3320);
FORCEPROP 1 LAST COMMENT_BODY TRUE
R 1
J 0
(-1870 3095);
DISPLAY 0.872340 (-1870 3095);
PAINT GREEN (-1870 3095);
DISPLAY INVISIBLE (-1870 3095);
FORCEPROP 2 LAST CDS_LIB mstr_misc
J 0
(-1945 3320);
PAINT ORANGE (-1945 3320);
DISPLAY INVISIBLE (-1945 3320);
FORCEADD DNS..2
(-5945 2795);
PAINT RED (-5945 2795);
FORCEPROP 1 LAST COMMENT_BODY TRUE
R 1
J 0
(-5870 2570);
DISPLAY 0.872340 (-5870 2570);
PAINT GREEN (-5870 2570);
DISPLAY INVISIBLE (-5870 2570);
FORCEPROP 2 LAST CDS_LIB mstr_misc
J 0
(-5945 2795);
PAINT ORANGE (-5945 2795);
DISPLAY INVISIBLE (-5945 2795);
FORCEADD DNS..2
(-2095 1245);
PAINT RED (-2095 1245);
FORCEPROP 2 LAST CDS_LIB mstr_misc
J 0
(-2095 1245);
PAINT ORANGE (-2095 1245);
DISPLAY INVISIBLE (-2095 1245);
FORCEPROP 1 LAST COMMENT_BODY TRUE
R 1
J 0
(-2020 1020);
DISPLAY 0.872340 (-2020 1020);
PAINT GREEN (-2020 1020);
DISPLAY INVISIBLE (-2020 1020);
FORCEADD CAD_NOTE..1
(-5325 2225);
FORCEPROP 0 LAST L1 PLACE CAP CLOSE
J 0
(-5475 2100);
DISPLAY 0.617021 (-5475 2100);
PAINT WHITE (-5475 2100);
FORCEPROP 0 LAST L2 TO IC
J 0
(-5475 2025);
DISPLAY 0.617021 (-5475 2025);
PAINT WHITE (-5475 2025);
FORCEPROP 1 LAST COMMENT_BODY TRUE
J 0
(-5300 2325);
DISPLAY 1.361702 (-5300 2325);
PAINT WHITE (-5300 2325);
DISPLAY INVISIBLE (-5300 2325);
FORCEPROP 2 LAST CDS_LIB mstr_symbols
J 0
(-5325 2225);
PAINT ORANGE (-5325 2225);
DISPLAY INVISIBLE (-5325 2225);
WIRE 16 -1 (-6200 575)(-6200 525);
WIRE 16 -1 (-6200 800)(-6200 775);
WIRE 16 -1 (-1375 2525)(-1375 2475);
WIRE 16 -1 (-1375 2475)(-1300 2475);
WIRE 16 -1 (-1375 1800)(-1375 2475);
WIRE 16 -1 (-1375 1800)(-875 1800);
WIRE 16 -1 (-1000 2475)(-1300 2475);
WIRE 16 -1 (-1300 2475)(-1300 2375);
WIRE 16 -1 (-1000 2375)(-1000 2475);
WIRE 16 -1 (-1500 4675)(-1500 4550);
WIRE 16 -1 (-1500 4550)(-1400 4550);
WIRE 16 -1 (-1500 3875)(-1500 4550);
WIRE 16 -1 (-1500 3875)(-825 3875);
WIRE 16 -1 (-1125 4550)(-1400 4550);
WIRE 16 -1 (-1400 4550)(-1400 4450);
WIRE 16 -1 (-1125 4425)(-1125 4550);
WIRE 16 -1 (-1150 1900)(-875 1900);
WIRE 16 -1 (-5775 2300)(-5775 2250);
WIRE 16 -1 (-5775 2050)(-5775 2000);
WIRE 16 -1 (-5950 2975)(-5950 2900);
WIRE 16 -1 (-1050 3975)(-825 3975);
WIRE 16 -1 (-1125 4150)(-1125 4125);
WIRE 16 -1 (-1125 4150)(-1400 4150);
WIRE 16 -1 (-1125 4225)(-1125 4150);
WIRE 16 -1 (-1400 4150)(-1400 4250);
WIRE 16 -1 (-1300 2075)(-1300 2000);
WIRE 16 -1 (-1300 2075)(-1000 2075);
WIRE 16 -1 (-1300 2075)(-1300 2175);
WIRE 16 -1 (-1000 2175)(-1000 2075);
WIRE 16 -1 (-2775 3525)(-2775 3425);
WIRE 16 -1 (-2900 4200)(-2900 4125);
WIRE 16 -1 (-1950 3575)(-1950 3500);
WIRE 16 -1 (-1950 3500)(-1950 3425);
WIRE 16 -1 (-2175 3500)(-1950 3500);
WIRE 16 -1 (-3050 2125)(-3050 2050);
WIRE 16 -1 (-2100 1500)(-2100 1425);
WIRE 16 -1 (-2325 1425)(-2100 1425);
WIRE 16 -1 (-2100 1425)(-2100 1350);
WIRE 16 -1 (-2325 1400)(-2325 1425);
WIRE 16 -1 (-2925 1450)(-2925 1350);
WIRE 16 -1 (-6300 4600)(-6300 4550);
WIRE 16 -1 (-6300 4350)(-6300 4300);
WIRE 16 -1 (-2325 1075)(-3550 1075);
FORCEPROP 0 LAST SIG_NAME FAN_PWM_OUT_SYS1_R
J 0
(-3535 1085);
DISPLAY 0.617021 (-3535 1085);
PAINT ORANGE (-3535 1085);
WIRE 16 -1 (-2325 1200)(-2325 1075);
WIRE 16 -1 (-2100 1075)(-2325 1075);
WIRE 16 -1 (-2100 1150)(-2100 1075);
WIRE 16 -1 (-1600 1075)(-2100 1075);
WIRE 16 -1 (-1600 1700)(-1600 1075);
WIRE 16 -1 (-1600 1700)(-875 1700);
WIRE 3 682 (-550 800)(-4300 800);
WIRE 3 682 (-550 500)(-550 800);
WIRE 3 682 (-4300 800)(-4300 500);
WIRE 3 682 (-4300 500)(-550 500);
WIRE 16 -1 (-2175 3225)(-3575 3225);
FORCEPROP 0 LAST SIG_NAME FAN_PWM_OUT_SYS0_R
J 0
(-3560 3235);
DISPLAY 0.617021 (-3560 3235);
PAINT ORANGE (-3560 3235);
WIRE 16 -1 (-2175 3300)(-2175 3225);
WIRE 16 -1 (-2175 3150)(-2175 3225);
WIRE 16 -1 (-1950 3150)(-2175 3150);
WIRE 16 -1 (-1950 3225)(-1950 3150);
WIRE 16 -1 (-1450 3150)(-1950 3150);
WIRE 16 -1 (-1450 3775)(-1450 3150);
WIRE 16 -1 (-1450 3775)(-825 3775);
WIRE 3 682 (-4300 3050)(-4300 2750);
WIRE 3 682 (-550 3050)(-4300 3050);
WIRE 3 682 (-4300 2750)(-550 2750);
WIRE 3 682 (-550 2750)(-550 3050);
WIRE 16 -1 (-2925 1650)(-2925 1750);
WIRE 16 -1 (-2925 1750)(-2775 1750);
WIRE 16 -1 (-3050 1750)(-2925 1750);
WIRE 16 -1 (-3050 1850)(-3050 1750);
WIRE 16 -1 (-3550 1750)(-3050 1750);
FORCEPROP 0 LAST SIG_NAME FAN_TACH2
J 0
(-3535 1760);
DISPLAY 0.617021 (-3535 1760);
PAINT ORANGE (-3535 1760);
WIRE 3 682 (-1200 3000)(-1200 2850);
WIRE 3 682 (-800 3000)(-1200 3000);
WIRE 3 682 (-1200 2850)(-800 2850);
WIRE 3 682 (-800 2850)(-800 3000);
WIRE 16 -1 (-1725 1750)(-875 1750);
FORCEPROP 0 LAST SIG_NAME FAN_TACH2_CPU1_D1
J 0
(-1485 1750);
DISPLAY 0.617021 (-1485 1750);
PAINT ORANGE (-1485 1750);
FORCEPROP 2 LASTPROP $XRERR UNIQUE?
J 0
(-1725 1750);
DISPLAY 0.638298 (-1725 1750);
PAINT MONO (-1725 1750);
DISPLAY INVISIBLE (-1725 1750);
WIRE 3 682 (-800 725)(-1050 725);
WIRE 3 682 (-800 625)(-800 725);
WIRE 3 682 (-1050 725)(-1050 625);
WIRE 3 682 (-1050 625)(-800 625);
WIRE 3 682 (-800 2050)(-800 1550);
WIRE 3 682 (-300 2050)(-800 2050);
WIRE 3 682 (-800 1550)(-300 1550);
WIRE 3 682 (-300 1550)(-300 2050);
WIRE 16 -1 (-1775 3825)(-2425 3825);
FORCEPROP 0 LAST SIG_NAME FAN_TACH0_CPU0_D2
J 0
(-2310 3835);
DISPLAY 0.617021 (-2310 3835);
PAINT ORANGE (-2310 3835);
FORCEPROP 2 LASTPROP $XRERR UNIQUE?
J 0
(-2550 3835);
DISPLAY 0.638298 (-2550 3835);
PAINT MONO (-2550 3835);
DISPLAY INVISIBLE (-2550 3835);
WIRE 16 -1 (-1575 3825)(-825 3825);
FORCEPROP 0 LAST SIG_NAME FAN_TACH0_CPU0_D1
J 0
(-1310 3835);
DISPLAY 0.617021 (-1310 3835);
PAINT ORANGE (-1310 3835);
FORCEPROP 2 LASTPROP $XRERR UNIQUE?
J 0
(-1550 3835);
DISPLAY 0.638298 (-1550 3835);
PAINT MONO (-1550 3835);
DISPLAY INVISIBLE (-1550 3835);
WIRE 16 -1 (-6100 2575)(-5950 2575);
WIRE 16 -1 (-5950 2575)(-5350 2575);
FORCEPROP 0 LAST SIG_NAME FM_ENABLE_FAN_POWER
J 0
(-5885 2585);
DISPLAY 0.617021 (-5885 2585);
PAINT ORANGE (-5885 2585);
WIRE 16 -1 (-5950 2700)(-5950 2575);
WIRE 3 682 (-750 3650)(-250 3650);
WIRE 3 682 (-750 4100)(-750 3650);
WIRE 3 682 (-250 3650)(-250 4100);
WIRE 3 682 (-250 4100)(-750 4100);
WIRE 16 -1 (-5350 3850)(-4850 3850);
FORCEPROP 0 LAST SIG_NAME FAN_PWM_OUT_SYS0_R
J 0
(-5285 3860);
DISPLAY 0.617021 (-5285 3860);
PAINT ORANGE (-5285 3860);
WIRE 16 -1 (-2775 3725)(-2775 3825);
WIRE 16 -1 (-2775 3825)(-2625 3825);
WIRE 16 -1 (-2900 3925)(-2900 3825);
WIRE 16 -1 (-2900 3825)(-2775 3825);
WIRE 16 -1 (-3600 3825)(-2900 3825);
FORCEPROP 0 LAST SIG_NAME FAN_TACH0
J 0
(-3585 3835);
DISPLAY 0.617021 (-3585 3835);
PAINT ORANGE (-3585 3835);
WIRE 16 -1 (-5500 1100)(-4950 1100);
FORCEPROP 0 LAST SIG_NAME FAN_PWM_OUT_SYS1_R
J 0
(-5435 1110);
DISPLAY 0.617021 (-5435 1110);
PAINT ORANGE (-5435 1110);
WIRE 16 -1 (-5700 1100)(-6275 1100);
FORCEPROP 0 LAST SIG_NAME FAN_PWM_OUT_SYS1_BUF
J 0
(-6210 1110);
DISPLAY 0.617021 (-6210 1110);
PAINT ORANGE (-6210 1110);
FORCEPROP 2 LASTPROP $XRERR UNIQUE?
J 0
(-6450 1110);
DISPLAY 0.638298 (-6450 1110);
PAINT MONO (-6450 1110);
DISPLAY INVISIBLE (-6450 1110);
WIRE 16 -1 (-7325 1100)(-6525 1100);
FORCEPROP 0 LAST SIG_NAME FAN_PWM_OUT_SYS1
J 0
(-7350 1110);
DISPLAY 0.617021 (-7350 1110);
PAINT ORANGE (-7350 1110);
WIRE 16 -1 (-6200 3850)(-5550 3850);
FORCEPROP 0 LAST SIG_NAME FAN_PWM_OUT_SYS0_BUF
J 0
(-6085 3850);
DISPLAY 0.617021 (-6085 3850);
PAINT ORANGE (-6085 3850);
FORCEPROP 2 LASTPROP $XRERR UNIQUE?
J 0
(-6325 3850);
DISPLAY 0.638298 (-6325 3850);
PAINT MONO (-6325 3850);
DISPLAY INVISIBLE (-6325 3850);
WIRE 16 -1 (-6400 2625)(-7100 2625);
FORCEPROP 0 LAST SIG_NAME FM_CTNR_PS_ON
J 0
(-7060 2635);
DISPLAY 0.617021 (-7060 2635);
PAINT ORANGE (-7060 2635);
WIRE 16 -1 (-7100 2525)(-6400 2525);
FORCEPROP 0 LAST SIG_NAME FM_DISABLE_FAN_N
J 0
(-7085 2535);
DISPLAY 0.617021 (-7085 2535);
PAINT ORANGE (-7085 2535);
WIRE 16 -1 (-7200 3850)(-6450 3850);
FORCEPROP 0 LAST SIG_NAME FAN_PWM_OUT_SYS0
J 0
(-7175 3860);
DISPLAY 0.617021 (-7175 3860);
PAINT ORANGE (-7175 3860);
WIRE 16 -1 (-1925 1750)(-2575 1750);
FORCEPROP 0 LAST SIG_NAME FAN_TACH2_CPU1_D2
J 0
(-2460 1760);
DISPLAY 0.617021 (-2460 1760);
PAINT ORANGE (-2460 1760);
FORCEPROP 2 LASTPROP $XRERR UNIQUE?
J 0
(-2700 1760);
DISPLAY 0.638298 (-2700 1760);
PAINT MONO (-2700 1760);
DISPLAY INVISIBLE (-2700 1760);
DOT 1 (-2100 1075);
DOT 1 (-2100 1425);
DOT 1 (-1125 4150);
DOT 1 (-2925 1750);
DOT 1 (-3050 1750);
DOT 1 (-1300 2475);
DOT 1 (-5950 2575);
DOT 1 (-2900 3825);
DOT 1 (-2775 3825);
DOT 1 (-1950 3500);
DOT 1 (-1500 4550);
DOT 1 (-1400 4550);
DOT 1 (-1300 2075);
DOT 1 (-1950 3150);
DOT 1 (-1375 2475);
DOT 1 (-2325 1075);
DOT 1 (-2175 3225);
FORCENOTE
TP FAB3 DELETE CIRCUIT 0901
(-4300 2700) 0;
DISPLAY LEFT (-4300 2700);
DISPLAY 0.638298 (-4300 2700);
PAINT RED (-4300 2700);
FORCENOTE
TP FAB3 CHANGE TO TP 0823
(-1200 2800) 0;
DISPLAY LEFT (-1200 2800);
DISPLAY 0.638298 (-1200 2800);
PAINT RED (-1200 2800);
FORCENOTE
TP FAB3 CHANGE TO TP 0823
(-1050 575) 0;
DISPLAY LEFT (-1050 575);
DISPLAY 0.638298 (-1050 575);
PAINT RED (-1050 575);
FORCENOTE
TP FAB3 CHANGE FROM 6 PIN TO 4 PIN 0823
(-1075 1500) 0;
DISPLAY LEFT (-1075 1500);
DISPLAY 0.638298 (-1075 1500);
PAINT RED (-1075 1500);
FORCENOTE
TP FAB3 EXCHANGE LOCATION TO J10W1 0824
(-1075 1450) 0;
DISPLAY LEFT (-1075 1450);
DISPLAY 0.638298 (-1075 1450);
PAINT RED (-1075 1450);
FORCENOTE
TP FAB3 CHANGE FROM 6 PIN TO 4 PIN 0823
(-950 3600) 0;
DISPLAY LEFT (-950 3600);
DISPLAY 0.638298 (-950 3600);
PAINT RED (-950 3600);
FORCENOTE
TP FAB3 EXCHANGE LOCATION TO J1F2 0824
(-950 3500) 0;
DISPLAY LEFT (-950 3500);
DISPLAY 0.638298 (-950 3500);
PAINT RED (-950 3500);
FORCENOTE
ROOM=CPU_FANS
(-7925 325) 0;
DISPLAY LEFT (-7925 325);
DISPLAY 1.021277 (-7925 325);
PAINT PURPLE (-7925 325);
FORCENOTE
BOM_COST=SM_THERM
(-7925 225) 0;
DISPLAY LEFT (-7925 225);
DISPLAY 1.021277 (-7925 225);
PAINT PURPLE (-7925 225);
FORCENOTE
TP FAB3 DELETE CIRCUIT 0902
(-4300 450) 0;
DISPLAY LEFT (-4300 450);
DISPLAY 0.638298 (-4300 450);
PAINT RED (-4300 450);
FORCENOTE
TP FAB3 EXCHANGE LOCATION TO J10W1 0824
(-950 3550) 0;
DISPLAY LEFT (-950 3550);
DISPLAY 0.638298 (-950 3550);
PAINT RED (-950 3550);
QUIT
